G04 ================== begin FILE IDENTIFICATION RECORD ==================*
G04 Layout Name:  x887571-005_osp.brd*
G04 Film Name:    assy-sht1*
G04 File Format:  Gerber RS274X*
G04 File Origin:  Cadence Allegro 16.3-S036*
G04 Origin Date:  Thu Jul 03 00:06:56 2014*
G04 *
G04 Layer:  MANUFACTURING/PEN7*
G04 Layer:  DRAWING FORMAT/OUTLINE*
G04 Layer:  DRAWING FORMAT/ASSY-SHT1*
G04 Layer:  DRAWING FORMAT/ASSY_TOP*
G04 *
G04 Offset:    (0.0000 0.0000)*
G04 Mirror:    No*
G04 Mode:      Positive*
G04 Rotation:  0*
G04 FullContactRelief:  No*
G04 UndefLineWidth:     4.0000*
G04 ================== end FILE IDENTIFICATION RECORD ====================*
%FSLAX25Y25*MOIN*%
%IR0*IPPOS*OFA0.00000B0.00000*MIA0B0*SFA1.00000B1.00000*%
%ADD10C,.01*%
%ADD11C,.02*%
%ADD12C,.012*%
%ADD13C,.0201*%
%ADD14C,.013*%
%ADD15C,.05*%
%ADD16C,.015*%
%ADD17C,.025*%
%ADD18C,.018*%
%ADD19C,.006*%
%ADD20C,.009*%
%ADD21C,.004*%
G75*
%LPD*%
G75*
G54D10*
G01X384900Y-690000D02*
Y-680000D01*
X380583Y-687167D01*
X386417D01*
G01X393000Y-690333D02*
X392767Y-690167D01*
Y-689833D01*
X393000Y-689667D01*
X393233Y-689833D01*
Y-690167D01*
X393000Y-690333D01*
G01X412000Y-680000D02*
Y-690000D01*
G01X409317Y-680000D02*
X414683D01*
G01X421500Y-690000D02*
X420567Y-689833D01*
X419750Y-689167D01*
X419050Y-688167D01*
X418583Y-687000D01*
X418350Y-685667D01*
Y-684333D01*
X418583Y-683000D01*
X419050Y-681833D01*
X419750Y-680833D01*
X420567Y-680167D01*
X421500Y-680000D01*
X422433Y-680167D01*
X423250Y-680833D01*
X423950Y-681833D01*
X424417Y-683000D01*
X424650Y-684333D01*
Y-685667D01*
X424417Y-687000D01*
X423950Y-688167D01*
X423250Y-689167D01*
X422433Y-689833D01*
X421500Y-690000D01*
G01X428667Y-680000D02*
Y-690000D01*
X433333D01*
G01X442833D02*
X438167D01*
Y-680000D01*
X442833D01*
G01X440967Y-684833D02*
X438167D01*
G01X447667Y-690000D02*
Y-680000D01*
X450583D01*
X451517Y-680500D01*
X452100Y-681167D01*
X452333Y-682500D01*
X452100Y-683833D01*
X451400Y-684667D01*
X450583Y-685167D01*
X447667D01*
G01X450583D02*
X452333Y-690000D01*
G01X456583D02*
X459500Y-680000D01*
X462417Y-690000D01*
G01X461367Y-686500D02*
X457633D01*
G01X466317Y-690000D02*
Y-680000D01*
X471683Y-690000D01*
Y-680000D01*
G01X481067Y-680833D02*
X480367Y-680333D01*
X479550Y-680000D01*
X478617D01*
X477567Y-680500D01*
X476750Y-681333D01*
X476167Y-682333D01*
X475700Y-684000D01*
X475583Y-685500D01*
X475817Y-687000D01*
X476167Y-688000D01*
X476867Y-689000D01*
X477683Y-689667D01*
X478500Y-690000D01*
X479317D01*
X480133Y-689667D01*
X480833Y-689167D01*
X481417Y-688500D01*
G01X490333Y-690000D02*
X485667D01*
Y-680000D01*
X490333D01*
G01X488467Y-684833D02*
X485667D01*
G01X495050Y-688667D02*
X495983Y-689500D01*
X497033Y-690000D01*
X497967D01*
X498900Y-689500D01*
X499600Y-688667D01*
X499950Y-687500D01*
X499717Y-686334D01*
X499133Y-685333D01*
X498083Y-684667D01*
X496683Y-684333D01*
X495867Y-683667D01*
X495517Y-682500D01*
X495750Y-681333D01*
X496333Y-680500D01*
X497150Y-680000D01*
X497967D01*
X498783Y-680333D01*
X499483Y-681167D01*
G01X380933Y-658000D02*
X381633Y-659167D01*
X382567Y-659833D01*
X383617Y-660000D01*
X384550Y-659833D01*
X385483Y-659000D01*
X386067Y-658000D01*
X386183Y-657000D01*
X385950Y-655834D01*
X385133Y-655000D01*
X384317Y-654667D01*
X383267D01*
G01X384317D02*
X385017Y-654167D01*
X385600Y-653334D01*
X385833Y-652333D01*
X385600Y-651333D01*
X385017Y-650500D01*
X383967Y-650000D01*
X382917Y-650167D01*
X381867Y-650833D01*
G01X393000Y-660333D02*
X392767Y-660167D01*
Y-659833D01*
X393000Y-659667D01*
X393233Y-659833D01*
Y-660167D01*
X393000Y-660333D01*
G01X409433Y-660000D02*
Y-650000D01*
X411767D01*
X412700Y-650500D01*
X413400Y-651167D01*
X413983Y-652167D01*
X414450Y-653334D01*
X414567Y-655000D01*
X414450Y-656667D01*
X413983Y-657833D01*
X413400Y-658834D01*
X412700Y-659500D01*
X411767Y-660000D01*
X409433D01*
G01X421500D02*
X420567Y-659833D01*
X419750Y-659167D01*
X419050Y-658167D01*
X418583Y-657000D01*
X418350Y-655667D01*
Y-654333D01*
X418583Y-653000D01*
X419050Y-651833D01*
X419750Y-650833D01*
X420567Y-650167D01*
X421500Y-650000D01*
X422433Y-650167D01*
X423250Y-650833D01*
X423950Y-651833D01*
X424417Y-653000D01*
X424650Y-654333D01*
Y-655667D01*
X424417Y-657000D01*
X423950Y-658167D01*
X423250Y-659167D01*
X422433Y-659833D01*
X421500Y-660000D01*
G01X437817D02*
Y-650000D01*
X443183Y-660000D01*
Y-650000D01*
G01X450000Y-660000D02*
X449067Y-659833D01*
X448250Y-659167D01*
X447550Y-658167D01*
X447083Y-657000D01*
X446850Y-655667D01*
Y-654333D01*
X447083Y-653000D01*
X447550Y-651833D01*
X448250Y-650833D01*
X449067Y-650167D01*
X450000Y-650000D01*
X450933Y-650167D01*
X451750Y-650833D01*
X452450Y-651833D01*
X452917Y-653000D01*
X453150Y-654333D01*
Y-655667D01*
X452917Y-657000D01*
X452450Y-658167D01*
X451750Y-659167D01*
X450933Y-659833D01*
X450000Y-660000D01*
G01X459500Y-650000D02*
Y-660000D01*
G01X456817Y-650000D02*
X462183D01*
G01X476050Y-658667D02*
X476983Y-659500D01*
X478033Y-660000D01*
X478967D01*
X479900Y-659500D01*
X480600Y-658667D01*
X480950Y-657500D01*
X480717Y-656334D01*
X480133Y-655333D01*
X479083Y-654667D01*
X477683Y-654333D01*
X476867Y-653667D01*
X476517Y-652500D01*
X476750Y-651333D01*
X477333Y-650500D01*
X478150Y-650000D01*
X478967D01*
X479783Y-650333D01*
X480483Y-651167D01*
G01X490567Y-650833D02*
X489867Y-650333D01*
X489050Y-650000D01*
X488117D01*
X487067Y-650500D01*
X486250Y-651333D01*
X485667Y-652333D01*
X485200Y-654000D01*
X485083Y-655500D01*
X485317Y-657000D01*
X485667Y-658000D01*
X486367Y-659000D01*
X487183Y-659667D01*
X488000Y-660000D01*
X488817D01*
X489633Y-659667D01*
X490333Y-659167D01*
X490917Y-658500D01*
G01X494583Y-660000D02*
X497500Y-650000D01*
X500417Y-660000D01*
G01X499367Y-656500D02*
X495633D01*
G01X504667Y-650000D02*
Y-660000D01*
X509333D01*
G01X518833D02*
X514167D01*
Y-650000D01*
X518833D01*
G01X516967Y-654833D02*
X514167D01*
G01X532933Y-660000D02*
Y-650000D01*
X535267D01*
X536200Y-650500D01*
X536900Y-651167D01*
X537483Y-652167D01*
X537950Y-653334D01*
X538067Y-655000D01*
X537950Y-656667D01*
X537483Y-657833D01*
X536900Y-658834D01*
X536200Y-659500D01*
X535267Y-660000D01*
X532933D01*
G01X542667D02*
Y-650000D01*
X545583D01*
X546517Y-650500D01*
X547100Y-651167D01*
X547333Y-652500D01*
X547100Y-653833D01*
X546400Y-654667D01*
X545583Y-655167D01*
X542667D01*
G01X545583D02*
X547333Y-660000D01*
G01X551583D02*
X554500Y-650000D01*
X557417Y-660000D01*
G01X556367Y-656500D02*
X552633D01*
G01X560500Y-650000D02*
X562133Y-660000D01*
X564000Y-650000D01*
X565867Y-660000D01*
X567500Y-650000D01*
G01X572100D02*
X574900D01*
G01X573500D02*
Y-660000D01*
G01X572100D02*
X574900D01*
G01X580317D02*
Y-650000D01*
X585683Y-660000D01*
Y-650000D01*
G01X593200Y-655000D02*
X595533D01*
Y-658000D01*
X594833Y-659000D01*
X594017Y-659667D01*
X592850Y-660000D01*
X591683Y-659667D01*
X590867Y-659000D01*
X590167Y-658000D01*
X589700Y-656833D01*
X589467Y-655500D01*
Y-654333D01*
X589700Y-653334D01*
X590167Y-652167D01*
X590867Y-651167D01*
X591567Y-650500D01*
X592500Y-650000D01*
X593317D01*
X594250Y-650333D01*
X594950Y-651000D01*
G01X381283Y-621667D02*
X381983Y-620667D01*
X382800Y-620167D01*
X383733Y-620000D01*
X384900Y-620333D01*
X385717Y-621167D01*
X385950Y-622167D01*
X385833Y-623167D01*
X385367Y-624000D01*
X383033Y-625667D01*
X381983Y-626833D01*
X381283Y-628500D01*
X381050Y-630000D01*
X385950D01*
G01X393000Y-630333D02*
X392767Y-630167D01*
Y-629833D01*
X393000Y-629667D01*
X393233Y-629833D01*
Y-630167D01*
X393000Y-630333D01*
G01X412933Y-624667D02*
X413400Y-624167D01*
X413750Y-623334D01*
X413983Y-622167D01*
X413750Y-621167D01*
X413283Y-620500D01*
X412467Y-620000D01*
X409317D01*
Y-630000D01*
X413167D01*
X413983Y-629333D01*
X414450Y-628333D01*
X414683Y-627167D01*
X414450Y-626000D01*
X413750Y-625000D01*
X412933Y-624667D01*
X409317D01*
G01X419167Y-630000D02*
Y-620000D01*
X422083D01*
X423017Y-620500D01*
X423600Y-621167D01*
X423833Y-622500D01*
X423600Y-623833D01*
X422900Y-624667D01*
X422083Y-625167D01*
X419167D01*
G01X422083D02*
X423833Y-630000D01*
G01X433333D02*
X428667D01*
Y-620000D01*
X433333D01*
G01X431467Y-624833D02*
X428667D01*
G01X437583Y-630000D02*
X440500Y-620000D01*
X443417Y-630000D01*
G01X442367Y-626500D02*
X438633D01*
G01X447433Y-630000D02*
Y-620000D01*
G01X451867D02*
X447433Y-626167D01*
G01X452567Y-630000D02*
X449417Y-623334D01*
G01X466083Y-630000D02*
X469000Y-620000D01*
X471917Y-630000D01*
G01X470867Y-626500D02*
X467133D01*
G01X476167Y-620000D02*
Y-630000D01*
X480833D01*
G01X485667Y-620000D02*
Y-630000D01*
X490333D01*
G01X504550Y-628667D02*
X505483Y-629500D01*
X506533Y-630000D01*
X507467D01*
X508400Y-629500D01*
X509100Y-628667D01*
X509450Y-627500D01*
X509217Y-626334D01*
X508633Y-625333D01*
X507583Y-624667D01*
X506183Y-624333D01*
X505367Y-623667D01*
X505017Y-622500D01*
X505250Y-621333D01*
X505833Y-620500D01*
X506650Y-620000D01*
X507467D01*
X508283Y-620333D01*
X508983Y-621167D01*
G01X514050Y-630000D02*
Y-620000D01*
G01X518950D02*
Y-630000D01*
G01Y-625000D02*
X514050D01*
G01X523083Y-630000D02*
X526000Y-620000D01*
X528917Y-630000D01*
G01X527867Y-626500D02*
X524133D01*
G01X533167Y-630000D02*
Y-620000D01*
X536083D01*
X537017Y-620500D01*
X537600Y-621167D01*
X537833Y-622500D01*
X537600Y-623833D01*
X536900Y-624667D01*
X536083Y-625167D01*
X533167D01*
G01X536083D02*
X537833Y-630000D01*
G01X542667D02*
Y-620000D01*
X545467D01*
X546400Y-620500D01*
X547100Y-621667D01*
X547333Y-623000D01*
X547100Y-624333D01*
X546517Y-625333D01*
X545467Y-625834D01*
X542667D01*
G01X566333Y-630000D02*
X561667D01*
Y-620000D01*
X566333D01*
G01X564467Y-624833D02*
X561667D01*
G01X570933Y-630000D02*
Y-620000D01*
X573267D01*
X574200Y-620500D01*
X574900Y-621167D01*
X575483Y-622167D01*
X575950Y-623334D01*
X576067Y-625000D01*
X575950Y-626667D01*
X575483Y-627833D01*
X574900Y-628834D01*
X574200Y-629500D01*
X573267Y-630000D01*
X570933D01*
G01X583700Y-625000D02*
X586033D01*
Y-628000D01*
X585333Y-629000D01*
X584517Y-629667D01*
X583350Y-630000D01*
X582183Y-629667D01*
X581367Y-629000D01*
X580667Y-628000D01*
X580200Y-626833D01*
X579967Y-625500D01*
Y-624333D01*
X580200Y-623334D01*
X580667Y-622167D01*
X581367Y-621167D01*
X582067Y-620500D01*
X583000Y-620000D01*
X583817D01*
X584750Y-620333D01*
X585450Y-621000D01*
G01X594833Y-630000D02*
X590167D01*
Y-620000D01*
X594833D01*
G01X592967Y-624833D02*
X590167D01*
G01X599550Y-628667D02*
X600483Y-629500D01*
X601533Y-630000D01*
X602467D01*
X603400Y-629500D01*
X604100Y-628667D01*
X604450Y-627500D01*
X604217Y-626334D01*
X603633Y-625333D01*
X602583Y-624667D01*
X601183Y-624333D01*
X600367Y-623667D01*
X600017Y-622500D01*
X600250Y-621333D01*
X600833Y-620500D01*
X601650Y-620000D01*
X602467D01*
X603283Y-620333D01*
X603983Y-621167D01*
G01X383500Y-600000D02*
Y-590000D01*
X382100Y-592000D01*
G01Y-600000D02*
X384900D01*
G01X393000Y-600333D02*
X392767Y-600167D01*
Y-599833D01*
X393000Y-599667D01*
X393233Y-599833D01*
Y-600167D01*
X393000Y-600333D01*
G01X409433Y-600000D02*
Y-590000D01*
X411767D01*
X412700Y-590500D01*
X413400Y-591167D01*
X413983Y-592167D01*
X414450Y-593334D01*
X414567Y-595000D01*
X414450Y-596667D01*
X413983Y-597833D01*
X413400Y-598834D01*
X412700Y-599500D01*
X411767Y-600000D01*
X409433D01*
G01X420100Y-590000D02*
X422900D01*
G01X421500D02*
Y-600000D01*
G01X420100D02*
X422900D01*
G01X427967D02*
Y-590000D01*
X431000Y-598333D01*
X434033Y-590000D01*
Y-600000D01*
G01X442833D02*
X438167D01*
Y-590000D01*
X442833D01*
G01X440967Y-594833D02*
X438167D01*
G01X447317Y-600000D02*
Y-590000D01*
X452683Y-600000D01*
Y-590000D01*
G01X457050Y-598667D02*
X457983Y-599500D01*
X459033Y-600000D01*
X459967D01*
X460900Y-599500D01*
X461600Y-598667D01*
X461950Y-597500D01*
X461717Y-596334D01*
X461133Y-595333D01*
X460083Y-594667D01*
X458683Y-594333D01*
X457867Y-593667D01*
X457517Y-592500D01*
X457750Y-591333D01*
X458333Y-590500D01*
X459150Y-590000D01*
X459967D01*
X460783Y-590333D01*
X461483Y-591167D01*
G01X467600Y-590000D02*
X470400D01*
G01X469000D02*
Y-600000D01*
G01X467600D02*
X470400D01*
G01X478500D02*
X477567Y-599833D01*
X476750Y-599167D01*
X476050Y-598167D01*
X475583Y-597000D01*
X475350Y-595667D01*
Y-594333D01*
X475583Y-593000D01*
X476050Y-591833D01*
X476750Y-590833D01*
X477567Y-590167D01*
X478500Y-590000D01*
X479433Y-590167D01*
X480250Y-590833D01*
X480950Y-591833D01*
X481417Y-593000D01*
X481650Y-594333D01*
Y-595667D01*
X481417Y-597000D01*
X480950Y-598167D01*
X480250Y-599167D01*
X479433Y-599833D01*
X478500Y-600000D01*
G01X485317D02*
Y-590000D01*
X490683Y-600000D01*
Y-590000D01*
G01X495050Y-598667D02*
X495983Y-599500D01*
X497033Y-600000D01*
X497967D01*
X498900Y-599500D01*
X499600Y-598667D01*
X499950Y-597500D01*
X499717Y-596334D01*
X499133Y-595333D01*
X498083Y-594667D01*
X496683Y-594333D01*
X495867Y-593667D01*
X495517Y-592500D01*
X495750Y-591333D01*
X496333Y-590500D01*
X497150Y-590000D01*
X497967D01*
X498783Y-590333D01*
X499483Y-591167D01*
G01X513583Y-600000D02*
X516500Y-590000D01*
X519417Y-600000D01*
G01X518367Y-596500D02*
X514633D01*
G01X523667Y-600000D02*
Y-590000D01*
X526583D01*
X527517Y-590500D01*
X528100Y-591167D01*
X528333Y-592500D01*
X528100Y-593833D01*
X527400Y-594667D01*
X526583Y-595167D01*
X523667D01*
G01X526583D02*
X528333Y-600000D01*
G01X537833D02*
X533167D01*
Y-590000D01*
X537833D01*
G01X535967Y-594833D02*
X533167D01*
G01X553100Y-590000D02*
X555900D01*
G01X554500D02*
Y-600000D01*
G01X553100D02*
X555900D01*
G01X561317D02*
Y-590000D01*
X566683Y-600000D01*
Y-590000D01*
G01X581600D02*
X584400D01*
G01X583000D02*
Y-600000D01*
G01X581600D02*
X584400D01*
G01X589817D02*
Y-590000D01*
X595183Y-600000D01*
Y-590000D01*
G01X604567Y-590833D02*
X603867Y-590333D01*
X603050Y-590000D01*
X602117D01*
X601067Y-590500D01*
X600250Y-591333D01*
X599667Y-592333D01*
X599200Y-594000D01*
X599083Y-595500D01*
X599317Y-597000D01*
X599667Y-598000D01*
X600367Y-599000D01*
X601183Y-599667D01*
X602000Y-600000D01*
X602817D01*
X603633Y-599667D01*
X604333Y-599167D01*
X604917Y-598500D01*
G01X609050Y-600000D02*
Y-590000D01*
G01X613950D02*
Y-600000D01*
G01Y-595000D02*
X609050D01*
G01X623333Y-600000D02*
X618667D01*
Y-590000D01*
X623333D01*
G01X621467Y-594833D02*
X618667D01*
G01X628050Y-598667D02*
X628983Y-599500D01*
X630033Y-600000D01*
X630967D01*
X631900Y-599500D01*
X632600Y-598667D01*
X632950Y-597500D01*
X632717Y-596334D01*
X632133Y-595333D01*
X631083Y-594667D01*
X629683Y-594333D01*
X628867Y-593667D01*
X628517Y-592500D01*
X628750Y-591333D01*
X629333Y-590500D01*
X630150Y-590000D01*
X630967D01*
X631783Y-590333D01*
X632483Y-591167D01*
G01X380933Y-560000D02*
Y-567167D01*
X381400Y-568667D01*
X382333Y-569667D01*
X383500Y-570000D01*
X384667Y-569667D01*
X385600Y-568667D01*
X386067Y-567167D01*
Y-560000D01*
G01X390317Y-570000D02*
Y-560000D01*
X395683Y-570000D01*
Y-560000D01*
G01X400167D02*
Y-570000D01*
X404833D01*
G01X414333D02*
X409667D01*
Y-560000D01*
X414333D01*
G01X412467Y-564833D02*
X409667D01*
G01X419050Y-568667D02*
X419983Y-569500D01*
X421033Y-570000D01*
X421967D01*
X422900Y-569500D01*
X423600Y-568667D01*
X423950Y-567500D01*
X423717Y-566334D01*
X423133Y-565333D01*
X422083Y-564667D01*
X420683Y-564333D01*
X419867Y-563667D01*
X419517Y-562500D01*
X419750Y-561333D01*
X420333Y-560500D01*
X421150Y-560000D01*
X421967D01*
X422783Y-560333D01*
X423483Y-561167D01*
G01X428550Y-568667D02*
X429483Y-569500D01*
X430533Y-570000D01*
X431467D01*
X432400Y-569500D01*
X433100Y-568667D01*
X433450Y-567500D01*
X433217Y-566334D01*
X432633Y-565333D01*
X431583Y-564667D01*
X430183Y-564333D01*
X429367Y-563667D01*
X429017Y-562500D01*
X429250Y-561333D01*
X429833Y-560500D01*
X430650Y-560000D01*
X431467D01*
X432283Y-560333D01*
X432983Y-561167D01*
G01X450000Y-570000D02*
X449067Y-569833D01*
X448250Y-569167D01*
X447550Y-568167D01*
X447083Y-567000D01*
X446850Y-565667D01*
Y-564333D01*
X447083Y-563000D01*
X447550Y-561833D01*
X448250Y-560833D01*
X449067Y-560167D01*
X450000Y-560000D01*
X450933Y-560167D01*
X451750Y-560833D01*
X452450Y-561833D01*
X452917Y-563000D01*
X453150Y-564333D01*
Y-565667D01*
X452917Y-567000D01*
X452450Y-568167D01*
X451750Y-569167D01*
X450933Y-569833D01*
X450000Y-570000D01*
G01X459500Y-560000D02*
Y-570000D01*
G01X456817Y-560000D02*
X462183D01*
G01X466550Y-570000D02*
Y-560000D01*
G01X471450D02*
Y-570000D01*
G01Y-565000D02*
X466550D01*
G01X480833Y-570000D02*
X476167D01*
Y-560000D01*
X480833D01*
G01X478967Y-564833D02*
X476167D01*
G01X485667Y-570000D02*
Y-560000D01*
X488583D01*
X489517Y-560500D01*
X490100Y-561167D01*
X490333Y-562500D01*
X490100Y-563833D01*
X489400Y-564667D01*
X488583Y-565167D01*
X485667D01*
G01X488583D02*
X490333Y-570000D01*
G01X494000Y-560000D02*
X495633Y-570000D01*
X497500Y-560000D01*
X499367Y-570000D01*
X501000Y-560000D01*
G01X505600D02*
X508400D01*
G01X507000D02*
Y-570000D01*
G01X505600D02*
X508400D01*
G01X514050Y-568667D02*
X514983Y-569500D01*
X516033Y-570000D01*
X516967D01*
X517900Y-569500D01*
X518600Y-568667D01*
X518950Y-567500D01*
X518717Y-566334D01*
X518133Y-565333D01*
X517083Y-564667D01*
X515683Y-564333D01*
X514867Y-563667D01*
X514517Y-562500D01*
X514750Y-561333D01*
X515333Y-560500D01*
X516150Y-560000D01*
X516967D01*
X517783Y-560333D01*
X518483Y-561167D01*
G01X528333Y-570000D02*
X523667D01*
Y-560000D01*
X528333D01*
G01X526467Y-564833D02*
X523667D01*
G01X542550Y-568667D02*
X543483Y-569500D01*
X544533Y-570000D01*
X545467D01*
X546400Y-569500D01*
X547100Y-568667D01*
X547450Y-567500D01*
X547217Y-566334D01*
X546633Y-565333D01*
X545583Y-564667D01*
X544183Y-564333D01*
X543367Y-563667D01*
X543017Y-562500D01*
X543250Y-561333D01*
X543833Y-560500D01*
X544650Y-560000D01*
X545467D01*
X546283Y-560333D01*
X546983Y-561167D01*
G01X552167Y-570000D02*
Y-560000D01*
X554967D01*
X555900Y-560500D01*
X556600Y-561667D01*
X556833Y-563000D01*
X556600Y-564333D01*
X556017Y-565333D01*
X554967Y-565834D01*
X552167D01*
G01X566333Y-570000D02*
X561667D01*
Y-560000D01*
X566333D01*
G01X564467Y-564833D02*
X561667D01*
G01X576067Y-560833D02*
X575367Y-560333D01*
X574550Y-560000D01*
X573617D01*
X572567Y-560500D01*
X571750Y-561333D01*
X571167Y-562333D01*
X570700Y-564000D01*
X570583Y-565500D01*
X570817Y-567000D01*
X571167Y-568000D01*
X571867Y-569000D01*
X572683Y-569667D01*
X573500Y-570000D01*
X574317D01*
X575133Y-569667D01*
X575833Y-569167D01*
X576417Y-568500D01*
G01X581600Y-560000D02*
X584400D01*
G01X583000D02*
Y-570000D01*
G01X581600D02*
X584400D01*
G01X590283D02*
Y-560000D01*
X594717D01*
G01X593083Y-564833D02*
X590283D01*
G01X600600Y-560000D02*
X603400D01*
G01X602000D02*
Y-570000D01*
G01X600600D02*
X603400D01*
G01X613833D02*
X609167D01*
Y-560000D01*
X613833D01*
G01X611967Y-564833D02*
X609167D01*
G01X618433Y-570000D02*
Y-560000D01*
X620767D01*
X621700Y-560500D01*
X622400Y-561167D01*
X622983Y-562167D01*
X623450Y-563334D01*
X623567Y-565000D01*
X623450Y-566667D01*
X622983Y-567833D01*
X622400Y-568834D01*
X621700Y-569500D01*
X620767Y-570000D01*
X618433D01*
G01X630500Y-570333D02*
X630267Y-570167D01*
Y-569833D01*
X630500Y-569667D01*
X630733Y-569833D01*
Y-570167D01*
X630500Y-570333D01*
G01Y-565834D02*
X630267Y-565667D01*
Y-565333D01*
X630500Y-565167D01*
X630733Y-565333D01*
Y-565667D01*
X630500Y-565834D01*
G01X396675Y-773667D02*
X400025Y-780000D01*
G01Y-773667D02*
X396675Y-780000D01*
G01X405775Y-773667D02*
X409125Y-780000D01*
G01Y-773667D02*
X405775Y-780000D01*
G01X414875Y-773667D02*
X418225Y-780000D01*
G01Y-773667D02*
X414875Y-780000D01*
G01X433522Y-776833D02*
X436202D01*
G01X434750Y-774775D02*
Y-778892D01*
G01X441840Y-780317D02*
X445860Y-770500D01*
G01X451498Y-776833D02*
X454402D01*
G01X396750Y-743334D02*
X400250Y-750000D01*
G01Y-743334D02*
X396750Y-750000D01*
G01X406250Y-743334D02*
X409750Y-750000D01*
G01Y-743334D02*
X406250Y-750000D01*
G01X425717Y-746667D02*
X428517D01*
G01X427000Y-744500D02*
Y-748834D01*
G01X434400Y-750333D02*
X438600Y-740000D01*
G01X444483Y-746667D02*
X447517D01*
G01X395583Y-720000D02*
X398500Y-710000D01*
X401417Y-720000D01*
G01X400367Y-716500D02*
X396633D01*
G01X405317Y-720000D02*
Y-710000D01*
X410683Y-720000D01*
Y-710000D01*
G01X418200Y-715000D02*
X420533D01*
Y-718000D01*
X419833Y-719000D01*
X419017Y-719667D01*
X417850Y-720000D01*
X416683Y-719667D01*
X415867Y-719000D01*
X415167Y-718000D01*
X414700Y-716833D01*
X414467Y-715500D01*
Y-714333D01*
X414700Y-713334D01*
X415167Y-712167D01*
X415867Y-711167D01*
X416567Y-710500D01*
X417500Y-710000D01*
X418317D01*
X419250Y-710333D01*
X419950Y-711000D01*
G01X424667Y-710000D02*
Y-720000D01*
X429333D01*
G01X438833D02*
X434167D01*
Y-710000D01*
X438833D01*
G01X436967Y-714833D02*
X434167D01*
G01X443550Y-718667D02*
X444483Y-719500D01*
X445533Y-720000D01*
X446467D01*
X447400Y-719500D01*
X448100Y-718667D01*
X448450Y-717500D01*
X448217Y-716334D01*
X447633Y-715333D01*
X446583Y-714667D01*
X445183Y-714333D01*
X444367Y-713667D01*
X444017Y-712500D01*
X444250Y-711333D01*
X444833Y-710500D01*
X445650Y-710000D01*
X446467D01*
X447283Y-710333D01*
X447983Y-711167D01*
G01X463717Y-716667D02*
X466517D01*
G01X465000Y-714500D02*
Y-718834D01*
G01X472400Y-720333D02*
X476600Y-710000D01*
G01X482483Y-716667D02*
X485517D01*
G01X610167Y1257000D02*
Y1267000D01*
X613083D01*
X614017Y1266500D01*
X614600Y1265833D01*
X614833Y1264500D01*
X614600Y1263167D01*
X613900Y1262333D01*
X613083Y1261833D01*
X610167D01*
G01X613083D02*
X614833Y1257000D01*
G01X624333D02*
X619667D01*
Y1267000D01*
X624333D01*
G01X622467Y1262167D02*
X619667D01*
G01X628583Y1267000D02*
X631500Y1257000D01*
X634417Y1267000D01*
G01X618613Y1228690D02*
X621530Y1238690D01*
X624447Y1228690D01*
G01X623397Y1232190D02*
X619663D01*
G01X645583Y-725000D02*
X648500Y-715000D01*
X651417Y-725000D01*
G01X650367Y-721500D02*
X646633D01*
G01X655667Y-725000D02*
Y-715000D01*
X658467D01*
X659400Y-715500D01*
X660100Y-716667D01*
X660333Y-718000D01*
X660100Y-719333D01*
X659517Y-720333D01*
X658467Y-720834D01*
X655667D01*
G01X664583Y-715000D02*
X667500Y-725000D01*
X670417Y-715000D01*
G01X674433Y-725000D02*
Y-715000D01*
X676767D01*
X677700Y-715500D01*
X678400Y-716167D01*
X678983Y-717167D01*
X679450Y-718334D01*
X679567Y-720000D01*
X679450Y-721667D01*
X678983Y-722833D01*
X678400Y-723834D01*
X677700Y-724500D01*
X676767Y-725000D01*
X674433D01*
G01X645583Y-695000D02*
X648500Y-685000D01*
X651417Y-695000D01*
G01X650367Y-691500D02*
X646633D01*
G01X655667Y-695000D02*
Y-685000D01*
X658467D01*
X659400Y-685500D01*
X660100Y-686667D01*
X660333Y-688000D01*
X660100Y-689333D01*
X659517Y-690333D01*
X658467Y-690834D01*
X655667D01*
G01X664583Y-685000D02*
X667500Y-695000D01*
X670417Y-685000D01*
G01X674433Y-695000D02*
Y-685000D01*
X676767D01*
X677700Y-685500D01*
X678400Y-686167D01*
X678983Y-687167D01*
X679450Y-688334D01*
X679567Y-690000D01*
X679450Y-691667D01*
X678983Y-692833D01*
X678400Y-693834D01*
X677700Y-694500D01*
X676767Y-695000D01*
X674433D01*
G01X645583Y-670000D02*
X648500Y-660000D01*
X651417Y-670000D01*
G01X650367Y-666500D02*
X646633D01*
G01X655667Y-670000D02*
Y-660000D01*
X658467D01*
X659400Y-660500D01*
X660100Y-661667D01*
X660333Y-663000D01*
X660100Y-664333D01*
X659517Y-665333D01*
X658467Y-665834D01*
X655667D01*
G01X664583Y-660000D02*
X667500Y-670000D01*
X670417Y-660000D01*
G01X674433Y-670000D02*
Y-660000D01*
X676767D01*
X677700Y-660500D01*
X678400Y-661167D01*
X678983Y-662167D01*
X679450Y-663334D01*
X679567Y-665000D01*
X679450Y-666667D01*
X678983Y-667833D01*
X678400Y-668834D01*
X677700Y-669500D01*
X676767Y-670000D01*
X674433D01*
G01X650833Y-655000D02*
X646167D01*
Y-645000D01*
X650833D01*
G01X648967Y-649833D02*
X646167D01*
G01X655317Y-655000D02*
Y-645000D01*
X660683Y-655000D01*
Y-645000D01*
G01X668200Y-650000D02*
X670533D01*
Y-653000D01*
X669833Y-654000D01*
X669017Y-654667D01*
X667850Y-655000D01*
X666683Y-654667D01*
X665867Y-654000D01*
X665167Y-653000D01*
X664700Y-651833D01*
X664467Y-650500D01*
Y-649333D01*
X664700Y-648334D01*
X665167Y-647167D01*
X665867Y-646167D01*
X666567Y-645500D01*
X667500Y-645000D01*
X668317D01*
X669250Y-645333D01*
X669950Y-646000D01*
G01X674667Y-655000D02*
Y-645000D01*
X677583D01*
X678517Y-645500D01*
X679100Y-646167D01*
X679333Y-647500D01*
X679100Y-648833D01*
X678400Y-649667D01*
X677583Y-650167D01*
X674667D01*
G01X677583D02*
X679333Y-655000D01*
G01X651067Y-620833D02*
X650367Y-620333D01*
X649550Y-620000D01*
X648617D01*
X647567Y-620500D01*
X646750Y-621333D01*
X646167Y-622333D01*
X645700Y-624000D01*
X645583Y-625500D01*
X645817Y-627000D01*
X646167Y-628000D01*
X646867Y-629000D01*
X647683Y-629667D01*
X648500Y-630000D01*
X649317D01*
X650133Y-629667D01*
X650833Y-629167D01*
X651417Y-628500D01*
G01X655550Y-630000D02*
Y-620000D01*
G01X660450D02*
Y-630000D01*
G01Y-625000D02*
X655550D01*
G01X664933Y-630000D02*
Y-620000D01*
G01X669367D02*
X664933Y-626167D01*
G01X670067Y-630000D02*
X666917Y-623334D01*
G01X687433Y-624667D02*
X687900Y-624167D01*
X688250Y-623334D01*
X688483Y-622167D01*
X688250Y-621167D01*
X687783Y-620500D01*
X686967Y-620000D01*
X683817D01*
Y-630000D01*
X687667D01*
X688483Y-629333D01*
X688950Y-628333D01*
X689183Y-627167D01*
X688950Y-626000D01*
X688250Y-625000D01*
X687433Y-624667D01*
X683817D01*
G01X696000Y-630000D02*
Y-625500D01*
X693667Y-620000D01*
G01X698333D02*
X696000Y-625500D01*
G01X705500Y-630333D02*
X705267Y-630167D01*
Y-629833D01*
X705500Y-629667D01*
X705733Y-629833D01*
Y-630167D01*
X705500Y-630333D01*
G01Y-625834D02*
X705267Y-625667D01*
Y-625333D01*
X705500Y-625167D01*
X705733Y-625333D01*
Y-625667D01*
X705500Y-625834D01*
G01X645933Y-600000D02*
Y-590000D01*
X648267D01*
X649200Y-590500D01*
X649900Y-591167D01*
X650483Y-592167D01*
X650950Y-593334D01*
X651067Y-595000D01*
X650950Y-596667D01*
X650483Y-597833D01*
X649900Y-598834D01*
X649200Y-599500D01*
X648267Y-600000D01*
X645933D01*
G01X655667D02*
Y-590000D01*
X658583D01*
X659517Y-590500D01*
X660100Y-591167D01*
X660333Y-592500D01*
X660100Y-593833D01*
X659400Y-594667D01*
X658583Y-595167D01*
X655667D01*
G01X658583D02*
X660333Y-600000D01*
G01X664817D02*
Y-590000D01*
X670183Y-600000D01*
Y-590000D01*
G01X687433Y-594667D02*
X687900Y-594167D01*
X688250Y-593334D01*
X688483Y-592167D01*
X688250Y-591167D01*
X687783Y-590500D01*
X686967Y-590000D01*
X683817D01*
Y-600000D01*
X687667D01*
X688483Y-599333D01*
X688950Y-598333D01*
X689183Y-597167D01*
X688950Y-596000D01*
X688250Y-595000D01*
X687433Y-594667D01*
X683817D01*
G01X696000Y-600000D02*
Y-595500D01*
X693667Y-590000D01*
G01X698333D02*
X696000Y-595500D01*
G01X705500Y-600333D02*
X705267Y-600167D01*
Y-599833D01*
X705500Y-599667D01*
X705733Y-599833D01*
Y-600167D01*
X705500Y-600333D01*
G01Y-595834D02*
X705267Y-595667D01*
Y-595333D01*
X705500Y-595167D01*
X705733Y-595333D01*
Y-595667D01*
X705500Y-595834D01*
G01X658900Y1239200D02*
X661700D01*
G01X660300D02*
Y1229200D01*
G01X658900D02*
X661700D01*
G01X667817D02*
Y1235866D01*
G01Y1234200D02*
X668283Y1235033D01*
X668983Y1235700D01*
X669917Y1235866D01*
X670733Y1235700D01*
X671433Y1235033D01*
X671783Y1233867D01*
Y1229200D01*
G01X679300Y1235866D02*
Y1229200D01*
G01Y1238533D02*
X679067Y1238700D01*
Y1239033D01*
X679300Y1239200D01*
X679533Y1239033D01*
Y1238700D01*
X679300Y1238533D01*
G01X688800Y1239200D02*
Y1229200D01*
G01X687167Y1235866D02*
X690433D01*
G01X698300D02*
Y1229200D01*
G01Y1238533D02*
X698067Y1238700D01*
Y1239033D01*
X698300Y1239200D01*
X698533Y1239033D01*
Y1238700D01*
X698300Y1238533D01*
G01X709900Y1229200D02*
Y1235866D01*
G01Y1234700D02*
X709433Y1235367D01*
X708733Y1235700D01*
X707917Y1235866D01*
X707100Y1235533D01*
X706400Y1234867D01*
X705933Y1233867D01*
X705700Y1232533D01*
X705933Y1231200D01*
X706400Y1230200D01*
X707100Y1229533D01*
X707917Y1229200D01*
X708733Y1229367D01*
X709433Y1229867D01*
X709900Y1230533D01*
G01X717300Y1229200D02*
Y1239200D01*
G01X733967Y1229200D02*
Y1239200D01*
X736883D01*
X737817Y1238700D01*
X738400Y1238033D01*
X738633Y1236700D01*
X738400Y1235367D01*
X737700Y1234533D01*
X736883Y1234033D01*
X733967D01*
G01X736883D02*
X738633Y1229200D01*
G01X744050Y1233700D02*
X747783D01*
X747433Y1234867D01*
X746850Y1235533D01*
X746033Y1235866D01*
X745217Y1235700D01*
X744517Y1235200D01*
X744050Y1234033D01*
X743817Y1233033D01*
Y1232033D01*
X744050Y1231033D01*
X744633Y1230033D01*
X745333Y1229367D01*
X746150Y1229200D01*
X746967Y1229533D01*
X747783Y1230533D01*
G01X755300Y1229200D02*
Y1239200D01*
G01X763050Y1233700D02*
X766783D01*
X766433Y1234867D01*
X765850Y1235533D01*
X765033Y1235866D01*
X764217Y1235700D01*
X763517Y1235200D01*
X763050Y1234033D01*
X762817Y1233033D01*
Y1232033D01*
X763050Y1231033D01*
X763633Y1230033D01*
X764333Y1229367D01*
X765150Y1229200D01*
X765967Y1229533D01*
X766783Y1230533D01*
G01X776400Y1229200D02*
Y1235866D01*
G01Y1234700D02*
X775933Y1235367D01*
X775233Y1235700D01*
X774417Y1235866D01*
X773600Y1235533D01*
X772900Y1234867D01*
X772433Y1233867D01*
X772200Y1232533D01*
X772433Y1231200D01*
X772900Y1230200D01*
X773600Y1229533D01*
X774417Y1229200D01*
X775233Y1229367D01*
X775933Y1229867D01*
X776400Y1230533D01*
G01X782050Y1230366D02*
X782633Y1229700D01*
X783450Y1229200D01*
X784150D01*
X784850Y1229533D01*
X785317Y1230033D01*
X785550Y1230700D01*
X785433Y1231700D01*
X784967Y1232200D01*
X782867Y1233200D01*
X782400Y1234367D01*
X782633Y1235200D01*
X783100Y1235700D01*
X783800Y1235866D01*
X784500Y1235700D01*
X785200Y1235200D01*
G01X791550Y1233700D02*
X795283D01*
X794933Y1234867D01*
X794350Y1235533D01*
X793533Y1235866D01*
X792717Y1235700D01*
X792017Y1235200D01*
X791550Y1234033D01*
X791317Y1233033D01*
Y1232033D01*
X791550Y1231033D01*
X792133Y1230033D01*
X792833Y1229367D01*
X793650Y1229200D01*
X794467Y1229533D01*
X795283Y1230533D01*
G01X679550Y-568667D02*
X680483Y-569500D01*
X681533Y-570000D01*
X682467D01*
X683400Y-569500D01*
X684100Y-568667D01*
X684450Y-567500D01*
X684217Y-566334D01*
X683633Y-565333D01*
X682583Y-564667D01*
X681183Y-564333D01*
X680367Y-563667D01*
X680017Y-562500D01*
X680250Y-561333D01*
X680833Y-560500D01*
X681650Y-560000D01*
X682467D01*
X683283Y-560333D01*
X683983Y-561167D01*
G01X690100Y-560000D02*
X692900D01*
G01X691500D02*
Y-570000D01*
G01X690100D02*
X692900D01*
G01X701700Y-565000D02*
X704033D01*
Y-568000D01*
X703333Y-569000D01*
X702517Y-569667D01*
X701350Y-570000D01*
X700183Y-569667D01*
X699367Y-569000D01*
X698667Y-568000D01*
X698200Y-566833D01*
X697967Y-565500D01*
Y-564333D01*
X698200Y-563334D01*
X698667Y-562167D01*
X699367Y-561167D01*
X700067Y-560500D01*
X701000Y-560000D01*
X701817D01*
X702750Y-560333D01*
X703450Y-561000D01*
G01X707817Y-570000D02*
Y-560000D01*
X713183Y-570000D01*
Y-560000D01*
G01X717083Y-570000D02*
X720000Y-560000D01*
X722917Y-570000D01*
G01X721867Y-566500D02*
X718133D01*
G01X729500Y-560000D02*
Y-570000D01*
G01X726817Y-560000D02*
X732183D01*
G01X736433D02*
Y-567167D01*
X736900Y-568667D01*
X737833Y-569667D01*
X739000Y-570000D01*
X740167Y-569667D01*
X741100Y-568667D01*
X741567Y-567167D01*
Y-560000D01*
G01X746167Y-570000D02*
Y-560000D01*
X749083D01*
X750017Y-560500D01*
X750600Y-561167D01*
X750833Y-562500D01*
X750600Y-563833D01*
X749900Y-564667D01*
X749083Y-565167D01*
X746167D01*
G01X749083D02*
X750833Y-570000D01*
G01X760333D02*
X755667D01*
Y-560000D01*
X760333D01*
G01X758467Y-564833D02*
X755667D01*
G01X727933Y1257000D02*
Y1267000D01*
X730267D01*
X731200Y1266500D01*
X731900Y1265833D01*
X732483Y1264833D01*
X732950Y1263666D01*
X733067Y1262000D01*
X732950Y1260333D01*
X732483Y1259167D01*
X731900Y1258166D01*
X731200Y1257500D01*
X730267Y1257000D01*
X727933D01*
G01X742333D02*
X737667D01*
Y1267000D01*
X742333D01*
G01X740467Y1262167D02*
X737667D01*
G01X747050Y1258333D02*
X747983Y1257500D01*
X749033Y1257000D01*
X749967D01*
X750900Y1257500D01*
X751600Y1258333D01*
X751950Y1259500D01*
X751717Y1260666D01*
X751133Y1261667D01*
X750083Y1262333D01*
X748683Y1262667D01*
X747867Y1263333D01*
X747517Y1264500D01*
X747750Y1265667D01*
X748333Y1266500D01*
X749150Y1267000D01*
X749967D01*
X750783Y1266667D01*
X751483Y1265833D01*
G01X761567Y1266167D02*
X760867Y1266667D01*
X760050Y1267000D01*
X759117D01*
X758067Y1266500D01*
X757250Y1265667D01*
X756667Y1264667D01*
X756200Y1263000D01*
X756083Y1261500D01*
X756317Y1260000D01*
X756667Y1259000D01*
X757367Y1258000D01*
X758183Y1257333D01*
X759000Y1257000D01*
X759817D01*
X760633Y1257333D01*
X761333Y1257833D01*
X761917Y1258500D01*
G01X766167Y1257000D02*
Y1267000D01*
X769083D01*
X770017Y1266500D01*
X770600Y1265833D01*
X770833Y1264500D01*
X770600Y1263167D01*
X769900Y1262333D01*
X769083Y1261833D01*
X766167D01*
G01X769083D02*
X770833Y1257000D01*
G01X776600Y1267000D02*
X779400D01*
G01X778000D02*
Y1257000D01*
G01X776600D02*
X779400D01*
G01X785167D02*
Y1267000D01*
X787967D01*
X788900Y1266500D01*
X789600Y1265333D01*
X789833Y1264000D01*
X789600Y1262667D01*
X789017Y1261667D01*
X787967Y1261166D01*
X785167D01*
G01X797000Y1267000D02*
Y1257000D01*
G01X794317Y1267000D02*
X799683D01*
G01X805100D02*
X807900D01*
G01X806500D02*
Y1257000D01*
G01X805100D02*
X807900D01*
G01X816000D02*
X815067Y1257167D01*
X814250Y1257833D01*
X813550Y1258833D01*
X813083Y1260000D01*
X812850Y1261333D01*
Y1262667D01*
X813083Y1264000D01*
X813550Y1265167D01*
X814250Y1266167D01*
X815067Y1266833D01*
X816000Y1267000D01*
X816933Y1266833D01*
X817750Y1266167D01*
X818450Y1265167D01*
X818917Y1264000D01*
X819150Y1262667D01*
Y1261333D01*
X818917Y1260000D01*
X818450Y1258833D01*
X817750Y1257833D01*
X816933Y1257167D01*
X816000Y1257000D01*
G01X822817D02*
Y1267000D01*
X828183Y1257000D01*
Y1267000D01*
G01X816250Y-600000D02*
Y-590000D01*
X814850Y-592000D01*
G01Y-600000D02*
X817650D01*
G01X825750Y-590000D02*
X824817Y-590333D01*
X824117Y-591167D01*
X823650Y-592167D01*
X823300Y-593500D01*
X823183Y-595000D01*
X823300Y-596500D01*
X823650Y-597833D01*
X824117Y-598834D01*
X824817Y-599667D01*
X825750Y-600000D01*
X826683Y-599667D01*
X827383Y-598834D01*
X827850Y-597833D01*
X828200Y-596500D01*
X828317Y-595000D01*
X828200Y-593500D01*
X827850Y-592167D01*
X827383Y-591167D01*
X826683Y-590333D01*
X825750Y-590000D01*
G01X833150Y-600333D02*
X837350Y-590000D01*
G01X844750D02*
X843817Y-590333D01*
X843117Y-591167D01*
X842650Y-592167D01*
X842300Y-593500D01*
X842183Y-595000D01*
X842300Y-596500D01*
X842650Y-597833D01*
X843117Y-598834D01*
X843817Y-599667D01*
X844750Y-600000D01*
X845683Y-599667D01*
X846383Y-598834D01*
X846850Y-597833D01*
X847200Y-596500D01*
X847317Y-595000D01*
X847200Y-593500D01*
X846850Y-592167D01*
X846383Y-591167D01*
X845683Y-590333D01*
X844750Y-590000D01*
G01X854250Y-600000D02*
Y-590000D01*
X852850Y-592000D01*
G01Y-600000D02*
X855650D01*
G01X861650Y-600333D02*
X865850Y-590000D01*
G01X873250Y-600000D02*
Y-590000D01*
X871850Y-592000D01*
G01Y-600000D02*
X874650D01*
G01X880183Y-598000D02*
X880883Y-599167D01*
X881817Y-599833D01*
X882867Y-600000D01*
X883800Y-599833D01*
X884733Y-599000D01*
X885317Y-598000D01*
X885433Y-597000D01*
X885200Y-595834D01*
X884383Y-595000D01*
X883567Y-594667D01*
X882517D01*
G01X883567D02*
X884267Y-594167D01*
X884850Y-593334D01*
X885083Y-592333D01*
X884850Y-591333D01*
X884267Y-590500D01*
X883217Y-590000D01*
X882167Y-590167D01*
X881117Y-590833D01*
G01X831183Y-570000D02*
Y-560000D01*
X833517D01*
X834450Y-560500D01*
X835150Y-561167D01*
X835733Y-562167D01*
X836200Y-563334D01*
X836317Y-565000D01*
X836200Y-566667D01*
X835733Y-567833D01*
X835150Y-568834D01*
X834450Y-569500D01*
X833517Y-570000D01*
X831183D01*
G01X840333D02*
X843250Y-560000D01*
X846167Y-570000D01*
G01X845117Y-566500D02*
X841383D01*
G01X852750Y-560000D02*
Y-570000D01*
G01X850067Y-560000D02*
X855433D01*
G01X864583Y-570000D02*
X859917D01*
Y-560000D01*
X864583D01*
G01X862717Y-564833D02*
X859917D01*
G01X896050Y-788667D02*
X896983Y-789500D01*
X898033Y-790000D01*
X898967D01*
X899900Y-789500D01*
X900600Y-788667D01*
X900950Y-787500D01*
X900717Y-786334D01*
X900133Y-785333D01*
X899083Y-784667D01*
X897683Y-784333D01*
X896867Y-783667D01*
X896517Y-782500D01*
X896750Y-781333D01*
X897333Y-780500D01*
X898150Y-780000D01*
X898967D01*
X899783Y-780333D01*
X900483Y-781167D01*
G01X910567Y-780833D02*
X909867Y-780333D01*
X909050Y-780000D01*
X908117D01*
X907067Y-780500D01*
X906250Y-781333D01*
X905667Y-782333D01*
X905200Y-784000D01*
X905083Y-785500D01*
X905317Y-787000D01*
X905667Y-788000D01*
X906367Y-789000D01*
X907183Y-789667D01*
X908000Y-790000D01*
X908817D01*
X909633Y-789667D01*
X910333Y-789167D01*
X910917Y-788500D01*
G01X914583Y-790000D02*
X917500Y-780000D01*
X920417Y-790000D01*
G01X919367Y-786500D02*
X915633D01*
G01X924667Y-780000D02*
Y-790000D01*
X929333D01*
G01X938833D02*
X934167D01*
Y-780000D01*
X938833D01*
G01X936967Y-784833D02*
X934167D01*
G01X946000Y-790333D02*
X945767Y-790167D01*
Y-789833D01*
X946000Y-789667D01*
X946233Y-789833D01*
Y-790167D01*
X946000Y-790333D01*
G01Y-785834D02*
X945767Y-785667D01*
Y-785333D01*
X946000Y-785167D01*
X946233Y-785333D01*
Y-785667D01*
X946000Y-785834D01*
G01X898800Y-733667D02*
X899733Y-734500D01*
X900783Y-735000D01*
X901717D01*
X902650Y-734500D01*
X903350Y-733667D01*
X903700Y-732500D01*
X903467Y-731334D01*
X902883Y-730333D01*
X901833Y-729667D01*
X900433Y-729333D01*
X899617Y-728667D01*
X899267Y-727500D01*
X899500Y-726333D01*
X900083Y-725500D01*
X900900Y-725000D01*
X901717D01*
X902533Y-725333D01*
X903233Y-726167D01*
G01X909350Y-725000D02*
X912150D01*
G01X910750D02*
Y-735000D01*
G01X909350D02*
X912150D01*
G01X918033Y-725000D02*
X922467D01*
X918033Y-735000D01*
X922467D01*
G01X932083D02*
X927417D01*
Y-725000D01*
X932083D01*
G01X930217Y-729833D02*
X927417D01*
G01X903500Y-630000D02*
Y-640000D01*
G01X900817Y-630000D02*
X906183D01*
G01X911600D02*
X914400D01*
G01X913000D02*
Y-640000D01*
G01X911600D02*
X914400D01*
G01X922500Y-630000D02*
Y-640000D01*
G01X919817Y-630000D02*
X925183D01*
G01X929667D02*
Y-640000D01*
X934333D01*
G01X943833D02*
X939167D01*
Y-630000D01*
X943833D01*
G01X941967Y-634833D02*
X939167D01*
G01X930933Y1257000D02*
Y1267000D01*
X933267D01*
X934200Y1266500D01*
X934900Y1265833D01*
X935483Y1264833D01*
X935950Y1263666D01*
X936067Y1262000D01*
X935950Y1260333D01*
X935483Y1259167D01*
X934900Y1258166D01*
X934200Y1257500D01*
X933267Y1257000D01*
X930933D01*
G01X940783D02*
Y1267000D01*
X945217D01*
G01X943583Y1262167D02*
X940783D01*
G01X952500Y1267000D02*
Y1257000D01*
G01X949817Y1267000D02*
X955183D01*
G01X948183Y-735000D02*
Y-725000D01*
X950517D01*
X951450Y-725500D01*
X952150Y-726167D01*
X952733Y-727167D01*
X953200Y-728334D01*
X953317Y-730000D01*
X953200Y-731667D01*
X952733Y-732833D01*
X952150Y-733834D01*
X951450Y-734500D01*
X950517Y-735000D01*
X948183D01*
G01X962817Y-725833D02*
X962117Y-725333D01*
X961300Y-725000D01*
X960367D01*
X959317Y-725500D01*
X958500Y-726333D01*
X957917Y-727333D01*
X957450Y-729000D01*
X957333Y-730500D01*
X957567Y-732000D01*
X957917Y-733000D01*
X958617Y-734000D01*
X959433Y-734667D01*
X960250Y-735000D01*
X961067D01*
X961883Y-734667D01*
X962583Y-734167D01*
X963167Y-733500D01*
G01X967417Y-725000D02*
Y-735000D01*
X972083D01*
G01X981817Y-725833D02*
X981117Y-725333D01*
X980300Y-725000D01*
X979367D01*
X978317Y-725500D01*
X977500Y-726333D01*
X976917Y-727333D01*
X976450Y-729000D01*
X976333Y-730500D01*
X976567Y-732000D01*
X976917Y-733000D01*
X977617Y-734000D01*
X978433Y-734667D01*
X979250Y-735000D01*
X980067D01*
X980883Y-734667D01*
X981583Y-734167D01*
X982167Y-733500D01*
G01X971167Y1282500D02*
Y1292500D01*
X974083D01*
X975017Y1292000D01*
X975600Y1291333D01*
X975833Y1290000D01*
X975600Y1288667D01*
X974900Y1287833D01*
X974083Y1287333D01*
X971167D01*
G01X974083D02*
X975833Y1282500D01*
G01X985333D02*
X980667D01*
Y1292500D01*
X985333D01*
G01X983467Y1287667D02*
X980667D01*
G01X989583Y1292500D02*
X992500Y1282500D01*
X995417Y1292500D01*
G01X1000600D02*
X1003400D01*
G01X1002000D02*
Y1282500D01*
G01X1000600D02*
X1003400D01*
G01X1009050Y1283833D02*
X1009983Y1283000D01*
X1011033Y1282500D01*
X1011967D01*
X1012900Y1283000D01*
X1013600Y1283833D01*
X1013950Y1285000D01*
X1013717Y1286166D01*
X1013133Y1287167D01*
X1012083Y1287833D01*
X1010683Y1288167D01*
X1009867Y1288833D01*
X1009517Y1290000D01*
X1009750Y1291167D01*
X1010333Y1292000D01*
X1011150Y1292500D01*
X1011967D01*
X1012783Y1292167D01*
X1013483Y1291333D01*
G01X1019600Y1292500D02*
X1022400D01*
G01X1021000D02*
Y1282500D01*
G01X1019600D02*
X1022400D01*
G01X1030500D02*
X1029567Y1282667D01*
X1028750Y1283333D01*
X1028050Y1284333D01*
X1027583Y1285500D01*
X1027350Y1286833D01*
Y1288167D01*
X1027583Y1289500D01*
X1028050Y1290667D01*
X1028750Y1291667D01*
X1029567Y1292333D01*
X1030500Y1292500D01*
X1031433Y1292333D01*
X1032250Y1291667D01*
X1032950Y1290667D01*
X1033417Y1289500D01*
X1033650Y1288167D01*
Y1286833D01*
X1033417Y1285500D01*
X1032950Y1284333D01*
X1032250Y1283333D01*
X1031433Y1282667D01*
X1030500Y1282500D01*
G01X1037317D02*
Y1292500D01*
X1042683Y1282500D01*
Y1292500D01*
G01X1047050Y1283833D02*
X1047983Y1283000D01*
X1049033Y1282500D01*
X1049967D01*
X1050900Y1283000D01*
X1051600Y1283833D01*
X1051950Y1285000D01*
X1051717Y1286166D01*
X1051133Y1287167D01*
X1050083Y1287833D01*
X1048683Y1288167D01*
X1047867Y1288833D01*
X1047517Y1290000D01*
X1047750Y1291167D01*
X1048333Y1292000D01*
X1049150Y1292500D01*
X1049967D01*
X1050783Y1292167D01*
X1051483Y1291333D01*
G01X1000817Y-725833D02*
X1000117Y-725333D01*
X999300Y-725000D01*
X998367D01*
X997317Y-725500D01*
X996500Y-726333D01*
X995917Y-727333D01*
X995450Y-729000D01*
X995333Y-730500D01*
X995567Y-732000D01*
X995917Y-733000D01*
X996617Y-734000D01*
X997433Y-734667D01*
X998250Y-735000D01*
X999067D01*
X999883Y-734667D01*
X1000583Y-734167D01*
X1001167Y-733500D01*
G01X1005417Y-725000D02*
Y-735000D01*
X1010083D01*
G01X1014333D02*
X1017250Y-725000D01*
X1020167Y-735000D01*
G01X1019117Y-731500D02*
X1015383D01*
G01X1024300Y-733667D02*
X1025233Y-734500D01*
X1026283Y-735000D01*
X1027217D01*
X1028150Y-734500D01*
X1028850Y-733667D01*
X1029200Y-732500D01*
X1028967Y-731334D01*
X1028383Y-730333D01*
X1027333Y-729667D01*
X1025933Y-729333D01*
X1025117Y-728667D01*
X1024767Y-727500D01*
X1025000Y-726333D01*
X1025583Y-725500D01*
X1026400Y-725000D01*
X1027217D01*
X1028033Y-725333D01*
X1028733Y-726167D01*
G01X1033800Y-733667D02*
X1034733Y-734500D01*
X1035783Y-735000D01*
X1036717D01*
X1037650Y-734500D01*
X1038350Y-733667D01*
X1038700Y-732500D01*
X1038467Y-731334D01*
X1037883Y-730333D01*
X1036833Y-729667D01*
X1035433Y-729333D01*
X1034617Y-728667D01*
X1034267Y-727500D01*
X1034500Y-726333D01*
X1035083Y-725500D01*
X1035900Y-725000D01*
X1036717D01*
X1037533Y-725333D01*
X1038233Y-726167D01*
G01X1057817Y-725833D02*
X1057117Y-725333D01*
X1056300Y-725000D01*
X1055367D01*
X1054317Y-725500D01*
X1053500Y-726333D01*
X1052917Y-727333D01*
X1052450Y-729000D01*
X1052333Y-730500D01*
X1052567Y-732000D01*
X1052917Y-733000D01*
X1053617Y-734000D01*
X1054433Y-734667D01*
X1055250Y-735000D01*
X1056067D01*
X1056883Y-734667D01*
X1057583Y-734167D01*
X1058167Y-733500D01*
G01X1064750Y-735000D02*
X1063817Y-734833D01*
X1063000Y-734167D01*
X1062300Y-733167D01*
X1061833Y-732000D01*
X1061600Y-730667D01*
Y-729333D01*
X1061833Y-728000D01*
X1062300Y-726833D01*
X1063000Y-725833D01*
X1063817Y-725167D01*
X1064750Y-725000D01*
X1065683Y-725167D01*
X1066500Y-725833D01*
X1067200Y-726833D01*
X1067667Y-728000D01*
X1067900Y-729333D01*
Y-730667D01*
X1067667Y-732000D01*
X1067200Y-733167D01*
X1066500Y-734167D01*
X1065683Y-734833D01*
X1064750Y-735000D01*
G01X1071683D02*
Y-725000D01*
X1074017D01*
X1074950Y-725500D01*
X1075650Y-726167D01*
X1076233Y-727167D01*
X1076700Y-728334D01*
X1076817Y-730000D01*
X1076700Y-731667D01*
X1076233Y-732833D01*
X1075650Y-733834D01*
X1074950Y-734500D01*
X1074017Y-735000D01*
X1071683D01*
G01X1086083D02*
X1081417D01*
Y-725000D01*
X1086083D01*
G01X1084217Y-729833D02*
X1081417D01*
G01X1007933Y1257000D02*
Y1267000D01*
X1010267D01*
X1011200Y1266500D01*
X1011900Y1265833D01*
X1012483Y1264833D01*
X1012950Y1263666D01*
X1013067Y1262000D01*
X1012950Y1260333D01*
X1012483Y1259167D01*
X1011900Y1258166D01*
X1011200Y1257500D01*
X1010267Y1257000D01*
X1007933D01*
G01X1017083D02*
X1020000Y1267000D01*
X1022917Y1257000D01*
G01X1021867Y1260500D02*
X1018133D01*
G01X1029500Y1267000D02*
Y1257000D01*
G01X1026817Y1267000D02*
X1032183D01*
G01X1041333Y1257000D02*
X1036667D01*
Y1267000D01*
X1041333D01*
G01X1039467Y1262167D02*
X1036667D01*
G01X1100067Y1266167D02*
X1099367Y1266667D01*
X1098550Y1267000D01*
X1097617D01*
X1096567Y1266500D01*
X1095750Y1265667D01*
X1095167Y1264667D01*
X1094700Y1263000D01*
X1094583Y1261500D01*
X1094817Y1260000D01*
X1095167Y1259000D01*
X1095867Y1258000D01*
X1096683Y1257333D01*
X1097500Y1257000D01*
X1098317D01*
X1099133Y1257333D01*
X1099833Y1257833D01*
X1100417Y1258500D01*
G01X1104550Y1257000D02*
Y1267000D01*
G01X1109450D02*
Y1257000D01*
G01Y1262000D02*
X1104550D01*
G01X1113933Y1257000D02*
Y1267000D01*
G01X1118367D02*
X1113933Y1260833D01*
G01X1119067Y1257000D02*
X1115917Y1263666D01*
G01X1108933Y-735000D02*
Y-725000D01*
X1111267D01*
X1112200Y-725500D01*
X1112900Y-726167D01*
X1113483Y-727167D01*
X1113950Y-728334D01*
X1114067Y-730000D01*
X1113950Y-731667D01*
X1113483Y-732833D01*
X1112900Y-733834D01*
X1112200Y-734500D01*
X1111267Y-735000D01*
X1108933D01*
G01X1121000D02*
X1120067Y-734833D01*
X1119250Y-734167D01*
X1118550Y-733167D01*
X1118083Y-732000D01*
X1117850Y-730667D01*
Y-729333D01*
X1118083Y-728000D01*
X1118550Y-726833D01*
X1119250Y-725833D01*
X1120067Y-725167D01*
X1121000Y-725000D01*
X1121933Y-725167D01*
X1122750Y-725833D01*
X1123450Y-726833D01*
X1123917Y-728000D01*
X1124150Y-729333D01*
Y-730667D01*
X1123917Y-732000D01*
X1123450Y-733167D01*
X1122750Y-734167D01*
X1121933Y-734833D01*
X1121000Y-735000D01*
G01X1133067Y-725833D02*
X1132367Y-725333D01*
X1131550Y-725000D01*
X1130617D01*
X1129567Y-725500D01*
X1128750Y-726333D01*
X1128167Y-727333D01*
X1127700Y-729000D01*
X1127583Y-730500D01*
X1127817Y-732000D01*
X1128167Y-733000D01*
X1128867Y-734000D01*
X1129683Y-734667D01*
X1130500Y-735000D01*
X1131317D01*
X1132133Y-734667D01*
X1132833Y-734167D01*
X1133417Y-733500D01*
G01X1137433Y-725000D02*
Y-732167D01*
X1137900Y-733667D01*
X1138833Y-734667D01*
X1140000Y-735000D01*
X1141167Y-734667D01*
X1142100Y-733667D01*
X1142567Y-732167D01*
Y-725000D01*
G01X1146467Y-735000D02*
Y-725000D01*
X1149500Y-733333D01*
X1152533Y-725000D01*
Y-735000D01*
G01X1161333D02*
X1156667D01*
Y-725000D01*
X1161333D01*
G01X1159467Y-729833D02*
X1156667D01*
G01X1165817Y-735000D02*
Y-725000D01*
X1171183Y-735000D01*
Y-725000D01*
G01X1178000D02*
Y-735000D01*
G01X1175317Y-725000D02*
X1180683D01*
G01X1194317Y-735000D02*
Y-725000D01*
X1199683Y-735000D01*
Y-725000D01*
G01X1203933D02*
Y-732167D01*
X1204400Y-733667D01*
X1205333Y-734667D01*
X1206500Y-735000D01*
X1207667Y-734667D01*
X1208600Y-733667D01*
X1209067Y-732167D01*
Y-725000D01*
G01X1212967Y-735000D02*
Y-725000D01*
X1216000Y-733333D01*
X1219033Y-725000D01*
Y-735000D01*
G01X1226433Y-729667D02*
X1226900Y-729167D01*
X1227250Y-728334D01*
X1227483Y-727167D01*
X1227250Y-726167D01*
X1226783Y-725500D01*
X1225967Y-725000D01*
X1222817D01*
Y-735000D01*
X1226667D01*
X1227483Y-734333D01*
X1227950Y-733333D01*
X1228183Y-732167D01*
X1227950Y-731000D01*
X1227250Y-730000D01*
X1226433Y-729667D01*
X1222817D01*
G01X1237333Y-735000D02*
X1232667D01*
Y-725000D01*
X1237333D01*
G01X1235467Y-729833D02*
X1232667D01*
G01X1242167Y-735000D02*
Y-725000D01*
X1245083D01*
X1246017Y-725500D01*
X1246600Y-726167D01*
X1246833Y-727500D01*
X1246600Y-728833D01*
X1245900Y-729667D01*
X1245083Y-730167D01*
X1242167D01*
G01X1245083D02*
X1246833Y-735000D01*
G01X1180933Y1257000D02*
Y1267000D01*
X1183267D01*
X1184200Y1266500D01*
X1184900Y1265833D01*
X1185483Y1264833D01*
X1185950Y1263666D01*
X1186067Y1262000D01*
X1185950Y1260333D01*
X1185483Y1259167D01*
X1184900Y1258166D01*
X1184200Y1257500D01*
X1183267Y1257000D01*
X1180933D01*
G01X1190083D02*
X1193000Y1267000D01*
X1195917Y1257000D01*
G01X1194867Y1260500D02*
X1191133D01*
G01X1202500Y1267000D02*
Y1257000D01*
G01X1199817Y1267000D02*
X1205183D01*
G01X1214333Y1257000D02*
X1209667D01*
Y1267000D01*
X1214333D01*
G01X1212467Y1262167D02*
X1209667D01*
G01X1215000Y-600000D02*
X1216633Y-610000D01*
X1218500Y-600000D01*
X1220367Y-610000D01*
X1222000Y-600000D01*
G01X1225083Y-610000D02*
X1228000Y-600000D01*
X1230917Y-610000D01*
G01X1229867Y-606500D02*
X1226133D01*
G01X1235050Y-608667D02*
X1235983Y-609500D01*
X1237033Y-610000D01*
X1237967D01*
X1238900Y-609500D01*
X1239600Y-608667D01*
X1239950Y-607500D01*
X1239717Y-606334D01*
X1239133Y-605333D01*
X1238083Y-604667D01*
X1236683Y-604333D01*
X1235867Y-603667D01*
X1235517Y-602500D01*
X1235750Y-601333D01*
X1236333Y-600500D01*
X1237150Y-600000D01*
X1237967D01*
X1238783Y-600333D01*
X1239483Y-601167D01*
G01X1244550Y-610000D02*
Y-600000D01*
G01X1249450D02*
Y-610000D01*
G01Y-605000D02*
X1244550D01*
G01X1273517Y-608834D02*
X1274333Y-609667D01*
X1275267Y-610000D01*
X1276200Y-609667D01*
X1277017Y-608667D01*
X1277600Y-607167D01*
X1277833Y-605667D01*
Y-603833D01*
X1277600Y-602333D01*
X1277017Y-601000D01*
X1276317Y-600333D01*
X1275500Y-600000D01*
X1274567Y-600333D01*
X1273867Y-601000D01*
X1273400Y-602000D01*
X1273167Y-603334D01*
X1273400Y-604500D01*
X1273983Y-605667D01*
X1274683Y-606334D01*
X1275500Y-606500D01*
X1276433Y-606167D01*
X1277133Y-605333D01*
X1277833Y-603833D01*
G01X1285000Y-610000D02*
X1285817Y-609833D01*
X1286750Y-609333D01*
X1287333Y-608500D01*
X1287567Y-607333D01*
X1287333Y-606167D01*
X1286633Y-605167D01*
X1285583Y-604667D01*
X1284417D01*
X1283717Y-604333D01*
X1283133Y-603500D01*
X1282900Y-602333D01*
X1283250Y-601167D01*
X1284067Y-600333D01*
X1285000Y-600000D01*
X1285933Y-600333D01*
X1286750Y-601167D01*
X1287100Y-602333D01*
X1286867Y-603500D01*
X1286283Y-604333D01*
X1285583Y-604667D01*
X1284417D01*
X1283367Y-605167D01*
X1282667Y-606167D01*
X1282433Y-607333D01*
X1282667Y-608500D01*
X1283250Y-609333D01*
X1284183Y-609833D01*
X1285000Y-610000D01*
G01X1294500Y-600000D02*
X1293567Y-600333D01*
X1292867Y-601167D01*
X1292400Y-602167D01*
X1292050Y-603500D01*
X1291933Y-605000D01*
X1292050Y-606500D01*
X1292400Y-607833D01*
X1292867Y-608834D01*
X1293567Y-609667D01*
X1294500Y-610000D01*
X1295433Y-609667D01*
X1296133Y-608834D01*
X1296600Y-607833D01*
X1296950Y-606500D01*
X1297067Y-605000D01*
X1296950Y-603500D01*
X1296600Y-602167D01*
X1296133Y-601167D01*
X1295433Y-600333D01*
X1294500Y-600000D01*
G01X1301433Y-608500D02*
X1302133Y-609333D01*
X1302950Y-609833D01*
X1304000Y-610000D01*
X1305050Y-609667D01*
X1305867Y-609000D01*
X1306450Y-607833D01*
X1306567Y-606500D01*
X1306333Y-605167D01*
X1305750Y-604333D01*
X1304933Y-603667D01*
X1304117Y-603500D01*
X1303300Y-603667D01*
X1302250Y-604333D01*
X1302600Y-600000D01*
X1305750D01*
G01X1311283Y-601667D02*
X1311983Y-600667D01*
X1312800Y-600167D01*
X1313733Y-600000D01*
X1314900Y-600333D01*
X1315717Y-601167D01*
X1315950Y-602167D01*
X1315833Y-603167D01*
X1315367Y-604000D01*
X1313033Y-605667D01*
X1311983Y-606833D01*
X1311283Y-608500D01*
X1311050Y-610000D01*
X1315950D01*
G01X1321483Y-606667D02*
X1324517D01*
G01X1330283Y-605834D02*
X1331100Y-604667D01*
X1331800Y-604000D01*
X1332733Y-603667D01*
X1333550Y-604000D01*
X1334133Y-604667D01*
X1334600Y-605667D01*
X1334717Y-606833D01*
X1334600Y-607833D01*
X1334133Y-608834D01*
X1333433Y-609667D01*
X1332617Y-610000D01*
X1331683Y-609667D01*
X1330867Y-608667D01*
X1330400Y-607167D01*
X1330283Y-605500D01*
X1330517Y-603334D01*
X1330867Y-602167D01*
X1331450Y-601000D01*
X1332267Y-600167D01*
X1333083Y-600000D01*
X1333900Y-600333D01*
X1334483Y-601167D01*
G01X1339433Y-608000D02*
X1340133Y-609167D01*
X1341067Y-609833D01*
X1342117Y-610000D01*
X1343050Y-609833D01*
X1343983Y-609000D01*
X1344567Y-608000D01*
X1344683Y-607000D01*
X1344450Y-605834D01*
X1343633Y-605000D01*
X1342817Y-604667D01*
X1341767D01*
G01X1342817D02*
X1343517Y-604167D01*
X1344100Y-603334D01*
X1344333Y-602333D01*
X1344100Y-601333D01*
X1343517Y-600500D01*
X1342467Y-600000D01*
X1341417Y-600167D01*
X1340367Y-600833D01*
G01X1349517Y-608834D02*
X1350333Y-609667D01*
X1351267Y-610000D01*
X1352200Y-609667D01*
X1353017Y-608667D01*
X1353600Y-607167D01*
X1353833Y-605667D01*
Y-603833D01*
X1353600Y-602333D01*
X1353017Y-601000D01*
X1352317Y-600333D01*
X1351500Y-600000D01*
X1350567Y-600333D01*
X1349867Y-601000D01*
X1349400Y-602000D01*
X1349167Y-603334D01*
X1349400Y-604500D01*
X1349983Y-605667D01*
X1350683Y-606334D01*
X1351500Y-606500D01*
X1352433Y-606167D01*
X1353133Y-605333D01*
X1353833Y-603833D01*
G01X1359017Y-608834D02*
X1359833Y-609667D01*
X1360767Y-610000D01*
X1361700Y-609667D01*
X1362517Y-608667D01*
X1363100Y-607167D01*
X1363333Y-605667D01*
Y-603833D01*
X1363100Y-602333D01*
X1362517Y-601000D01*
X1361817Y-600333D01*
X1361000Y-600000D01*
X1360067Y-600333D01*
X1359367Y-601000D01*
X1358900Y-602000D01*
X1358667Y-603334D01*
X1358900Y-604500D01*
X1359483Y-605667D01*
X1360183Y-606334D01*
X1361000Y-606500D01*
X1361933Y-606167D01*
X1362633Y-605333D01*
X1363333Y-603833D01*
G01X1216167Y-590000D02*
Y-580000D01*
X1219083D01*
X1220017Y-580500D01*
X1220600Y-581167D01*
X1220833Y-582500D01*
X1220600Y-583833D01*
X1219900Y-584667D01*
X1219083Y-585167D01*
X1216167D01*
G01X1219083D02*
X1220833Y-590000D01*
G01X1230333D02*
X1225667D01*
Y-580000D01*
X1230333D01*
G01X1228467Y-584833D02*
X1225667D01*
G01X1234933Y-590000D02*
Y-580000D01*
X1237267D01*
X1238200Y-580500D01*
X1238900Y-581167D01*
X1239483Y-582167D01*
X1239950Y-583334D01*
X1240067Y-585000D01*
X1239950Y-586667D01*
X1239483Y-587833D01*
X1238900Y-588834D01*
X1238200Y-589500D01*
X1237267Y-590000D01*
X1234933D01*
G01X1243967D02*
Y-580000D01*
X1247000Y-588333D01*
X1250033Y-580000D01*
Y-590000D01*
G01X1256500D02*
X1255567Y-589833D01*
X1254750Y-589167D01*
X1254050Y-588167D01*
X1253583Y-587000D01*
X1253350Y-585667D01*
Y-584333D01*
X1253583Y-583000D01*
X1254050Y-581833D01*
X1254750Y-580833D01*
X1255567Y-580167D01*
X1256500Y-580000D01*
X1257433Y-580167D01*
X1258250Y-580833D01*
X1258950Y-581833D01*
X1259417Y-583000D01*
X1259650Y-584333D01*
Y-585667D01*
X1259417Y-587000D01*
X1258950Y-588167D01*
X1258250Y-589167D01*
X1257433Y-589833D01*
X1256500Y-590000D01*
G01X1263317D02*
Y-580000D01*
X1268683Y-590000D01*
Y-580000D01*
G01X1272933Y-590000D02*
Y-580000D01*
X1275267D01*
X1276200Y-580500D01*
X1276900Y-581167D01*
X1277483Y-582167D01*
X1277950Y-583334D01*
X1278067Y-585000D01*
X1277950Y-586667D01*
X1277483Y-587833D01*
X1276900Y-588834D01*
X1276200Y-589500D01*
X1275267Y-590000D01*
X1272933D01*
G01X1218500Y-570000D02*
Y-560000D01*
X1217100Y-562000D01*
G01Y-570000D02*
X1219900D01*
G01X1234467D02*
Y-560000D01*
X1237500Y-568333D01*
X1240533Y-560000D01*
Y-570000D01*
G01X1245600Y-560000D02*
X1248400D01*
G01X1247000D02*
Y-570000D01*
G01X1245600D02*
X1248400D01*
G01X1259067Y-560833D02*
X1258367Y-560333D01*
X1257550Y-560000D01*
X1256617D01*
X1255567Y-560500D01*
X1254750Y-561333D01*
X1254167Y-562333D01*
X1253700Y-564000D01*
X1253583Y-565500D01*
X1253817Y-567000D01*
X1254167Y-568000D01*
X1254867Y-569000D01*
X1255683Y-569667D01*
X1256500Y-570000D01*
X1257317D01*
X1258133Y-569667D01*
X1258833Y-569167D01*
X1259417Y-568500D01*
G01X1263667Y-570000D02*
Y-560000D01*
X1266583D01*
X1267517Y-560500D01*
X1268100Y-561167D01*
X1268333Y-562500D01*
X1268100Y-563833D01*
X1267400Y-564667D01*
X1266583Y-565167D01*
X1263667D01*
G01X1266583D02*
X1268333Y-570000D01*
G01X1275500D02*
X1274567Y-569833D01*
X1273750Y-569167D01*
X1273050Y-568167D01*
X1272583Y-567000D01*
X1272350Y-565667D01*
Y-564333D01*
X1272583Y-563000D01*
X1273050Y-561833D01*
X1273750Y-560833D01*
X1274567Y-560167D01*
X1275500Y-560000D01*
X1276433Y-560167D01*
X1277250Y-560833D01*
X1277950Y-561833D01*
X1278417Y-563000D01*
X1278650Y-564333D01*
Y-565667D01*
X1278417Y-567000D01*
X1277950Y-568167D01*
X1277250Y-569167D01*
X1276433Y-569833D01*
X1275500Y-570000D01*
G01X1282550Y-568667D02*
X1283483Y-569500D01*
X1284533Y-570000D01*
X1285467D01*
X1286400Y-569500D01*
X1287100Y-568667D01*
X1287450Y-567500D01*
X1287217Y-566334D01*
X1286633Y-565333D01*
X1285583Y-564667D01*
X1284183Y-564333D01*
X1283367Y-563667D01*
X1283017Y-562500D01*
X1283250Y-561333D01*
X1283833Y-560500D01*
X1284650Y-560000D01*
X1285467D01*
X1286283Y-560333D01*
X1286983Y-561167D01*
G01X1294500Y-570000D02*
X1293567Y-569833D01*
X1292750Y-569167D01*
X1292050Y-568167D01*
X1291583Y-567000D01*
X1291350Y-565667D01*
Y-564333D01*
X1291583Y-563000D01*
X1292050Y-561833D01*
X1292750Y-560833D01*
X1293567Y-560167D01*
X1294500Y-560000D01*
X1295433Y-560167D01*
X1296250Y-560833D01*
X1296950Y-561833D01*
X1297417Y-563000D01*
X1297650Y-564333D01*
Y-565667D01*
X1297417Y-567000D01*
X1296950Y-568167D01*
X1296250Y-569167D01*
X1295433Y-569833D01*
X1294500Y-570000D01*
G01X1301783D02*
Y-560000D01*
X1306217D01*
G01X1304583Y-564833D02*
X1301783D01*
G01X1313500Y-560000D02*
Y-570000D01*
G01X1310817Y-560000D02*
X1316183D01*
G01X1329000D02*
X1330633Y-570000D01*
X1332500Y-560000D01*
X1334367Y-570000D01*
X1336000Y-560000D01*
G01X1339083Y-570000D02*
X1342000Y-560000D01*
X1344917Y-570000D01*
G01X1343867Y-566500D02*
X1340133D01*
G01X1351500Y-570000D02*
Y-565500D01*
X1349167Y-560000D01*
G01X1353833D02*
X1351500Y-565500D01*
G01X1233050Y-788667D02*
X1233983Y-789500D01*
X1235033Y-790000D01*
X1235967D01*
X1236900Y-789500D01*
X1237600Y-788667D01*
X1237950Y-787500D01*
X1237717Y-786334D01*
X1237133Y-785333D01*
X1236083Y-784667D01*
X1234683Y-784333D01*
X1233867Y-783667D01*
X1233517Y-782500D01*
X1233750Y-781333D01*
X1234333Y-780500D01*
X1235150Y-780000D01*
X1235967D01*
X1236783Y-780333D01*
X1237483Y-781167D01*
G01X1242550Y-790000D02*
Y-780000D01*
G01X1247450D02*
Y-790000D01*
G01Y-785000D02*
X1242550D01*
G01X1256833Y-790000D02*
X1252167D01*
Y-780000D01*
X1256833D01*
G01X1254967Y-784833D02*
X1252167D01*
G01X1266333Y-790000D02*
X1261667D01*
Y-780000D01*
X1266333D01*
G01X1264467Y-784833D02*
X1261667D01*
G01X1273500Y-780000D02*
Y-790000D01*
G01X1270817Y-780000D02*
X1276183D01*
G01X1254273Y1256940D02*
X1257190Y1266940D01*
X1260107Y1256940D01*
G01X1259057Y1260440D02*
X1255323D01*
G01X1264357Y1256940D02*
Y1266940D01*
X1267157D01*
X1268090Y1266440D01*
X1268790Y1265273D01*
X1269023Y1263940D01*
X1268790Y1262607D01*
X1268207Y1261607D01*
X1267157Y1261106D01*
X1264357D01*
G01X1273273Y1266940D02*
X1276190Y1256940D01*
X1279107Y1266940D01*
G01X1283123Y1256940D02*
Y1266940D01*
X1285457D01*
X1286390Y1266440D01*
X1287090Y1265773D01*
X1287673Y1264773D01*
X1288140Y1263606D01*
X1288257Y1261940D01*
X1288140Y1260273D01*
X1287673Y1259107D01*
X1287090Y1258106D01*
X1286390Y1257440D01*
X1285457Y1256940D01*
X1283123D01*
G01X1333500Y-790000D02*
X1332567Y-789833D01*
X1331750Y-789167D01*
X1331050Y-788167D01*
X1330583Y-787000D01*
X1330350Y-785667D01*
Y-784333D01*
X1330583Y-783000D01*
X1331050Y-781833D01*
X1331750Y-780833D01*
X1332567Y-780167D01*
X1333500Y-780000D01*
X1334433Y-780167D01*
X1335250Y-780833D01*
X1335950Y-781833D01*
X1336417Y-783000D01*
X1336650Y-784333D01*
Y-785667D01*
X1336417Y-787000D01*
X1335950Y-788167D01*
X1335250Y-789167D01*
X1334433Y-789833D01*
X1333500Y-790000D01*
G01X1340783D02*
Y-780000D01*
X1345217D01*
G01X1343583Y-784833D02*
X1340783D01*
G01X1324570Y1229100D02*
Y1239100D01*
X1323170Y1237100D01*
G01Y1229100D02*
X1325970D01*
G01X1334070Y1239100D02*
X1333137Y1238767D01*
X1332437Y1237933D01*
X1331970Y1236933D01*
X1331620Y1235600D01*
X1331503Y1234100D01*
X1331620Y1232600D01*
X1331970Y1231267D01*
X1332437Y1230266D01*
X1333137Y1229433D01*
X1334070Y1229100D01*
X1335003Y1229433D01*
X1335703Y1230266D01*
X1336170Y1231267D01*
X1336520Y1232600D01*
X1336637Y1234100D01*
X1336520Y1235600D01*
X1336170Y1236933D01*
X1335703Y1237933D01*
X1335003Y1238767D01*
X1334070Y1239100D01*
G01X1341470Y1228767D02*
X1345670Y1239100D01*
G01X1353070Y1229100D02*
Y1239100D01*
X1351670Y1237100D01*
G01Y1229100D02*
X1354470D01*
G01X1360470Y1228767D02*
X1364670Y1239100D01*
G01X1372070Y1229100D02*
Y1239100D01*
X1370670Y1237100D01*
G01Y1229100D02*
X1373470D01*
G01X1379003Y1231100D02*
X1379703Y1229933D01*
X1380637Y1229267D01*
X1381687Y1229100D01*
X1382620Y1229267D01*
X1383553Y1230100D01*
X1384137Y1231100D01*
X1384253Y1232100D01*
X1384020Y1233266D01*
X1383203Y1234100D01*
X1382387Y1234433D01*
X1381337D01*
G01X1382387D02*
X1383087Y1234933D01*
X1383670Y1235766D01*
X1383903Y1236767D01*
X1383670Y1237767D01*
X1383087Y1238600D01*
X1382037Y1239100D01*
X1380987Y1238933D01*
X1379937Y1238267D01*
G01X1343393Y1257230D02*
Y1267230D01*
X1345727D01*
X1346660Y1266730D01*
X1347360Y1266063D01*
X1347943Y1265063D01*
X1348410Y1263896D01*
X1348527Y1262230D01*
X1348410Y1260563D01*
X1347943Y1259397D01*
X1347360Y1258396D01*
X1346660Y1257730D01*
X1345727Y1257230D01*
X1343393D01*
G01X1352543D02*
X1355460Y1267230D01*
X1358377Y1257230D01*
G01X1357327Y1260730D02*
X1353593D01*
G01X1364960Y1267230D02*
Y1257230D01*
G01X1362277Y1267230D02*
X1367643D01*
G01X1376793Y1257230D02*
X1372127D01*
Y1267230D01*
X1376793D01*
G01X1374927Y1262397D02*
X1372127D01*
G01X1366167Y-735000D02*
Y-725000D01*
X1369083D01*
X1370017Y-725500D01*
X1370600Y-726167D01*
X1370833Y-727500D01*
X1370600Y-728833D01*
X1369900Y-729667D01*
X1369083Y-730167D01*
X1366167D01*
G01X1369083D02*
X1370833Y-735000D01*
G01X1380333D02*
X1375667D01*
Y-725000D01*
X1380333D01*
G01X1378467Y-729833D02*
X1375667D01*
G01X1384583Y-725000D02*
X1387500Y-735000D01*
X1390417Y-725000D01*
G54D20*
G01X724695Y-600500D02*
Y-591500D01*
G01X729105D02*
Y-600500D01*
G01Y-596000D02*
X724695D01*
G01X735500Y-600800D02*
X735290Y-600650D01*
Y-600350D01*
X735500Y-600200D01*
X735710Y-600350D01*
Y-600650D01*
X735500Y-600800D01*
G01X742105Y-600500D02*
Y-591500D01*
X746095D01*
G01X744625Y-595850D02*
X742105D01*
G01X750600Y-591500D02*
Y-600500D01*
X754800D01*
G01X761300D02*
X760460Y-600350D01*
X759725Y-599750D01*
X759095Y-598850D01*
X758675Y-597800D01*
X758465Y-596600D01*
Y-595400D01*
X758675Y-594200D01*
X759095Y-593150D01*
X759725Y-592250D01*
X760460Y-591650D01*
X761300Y-591500D01*
X762140Y-591650D01*
X762875Y-592250D01*
X763505Y-593150D01*
X763925Y-594200D01*
X764135Y-595400D01*
Y-596600D01*
X763925Y-597800D01*
X763505Y-598850D01*
X762875Y-599750D01*
X762140Y-600350D01*
X761300Y-600500D01*
G01X767800D02*
Y-591500D01*
X770425D01*
X771265Y-591950D01*
X771790Y-592550D01*
X772000Y-593750D01*
X771790Y-594950D01*
X771160Y-595700D01*
X770425Y-596150D01*
X767800D01*
G01X770425D02*
X772000Y-600500D01*
G01X777240Y-591500D02*
X779760D01*
G01X778500D02*
Y-600500D01*
G01X777240D02*
X779760D01*
G01X787100D02*
X786260Y-600350D01*
X785525Y-599750D01*
X784895Y-598850D01*
X784475Y-597800D01*
X784265Y-596600D01*
Y-595400D01*
X784475Y-594200D01*
X784895Y-593150D01*
X785525Y-592250D01*
X786260Y-591650D01*
X787100Y-591500D01*
X787940Y-591650D01*
X788675Y-592250D01*
X789305Y-593150D01*
X789725Y-594200D01*
X789935Y-595400D01*
Y-596600D01*
X789725Y-597800D01*
X789305Y-598850D01*
X788675Y-599750D01*
X787940Y-600350D01*
X787100Y-600500D01*
G54D11*
G01X1400000Y1220000D02*
X595000D01*
G01Y1240000D02*
Y1220000D01*
G01Y1300000D02*
Y1240000D01*
G01X1400000Y1250000D02*
X595000D01*
G01Y1275000D02*
X1400000D01*
G01X650000Y1250000D02*
Y1220000D01*
G01Y1275000D02*
Y1250000D01*
G01X890000D02*
Y1220000D01*
G01Y1275000D02*
Y1250000D01*
G01X911867Y-760000D02*
Y-740000D01*
X916533D01*
X918400Y-741000D01*
X919800Y-742333D01*
X920967Y-744333D01*
X921900Y-746667D01*
X922133Y-750000D01*
X921900Y-753334D01*
X920967Y-755667D01*
X919800Y-757667D01*
X918400Y-759000D01*
X916533Y-760000D01*
X911867D01*
G01X990000Y1250000D02*
Y1220000D01*
G01Y1275000D02*
Y1250000D01*
G01X1060000D02*
Y1220000D01*
G01Y1275000D02*
Y1250000D01*
G01X1160000D02*
Y1220000D01*
G01Y1275000D02*
Y1250000D01*
G01X1166100Y-762000D02*
X1175900Y-742000D01*
G01X1166100D02*
X1175900Y-762000D01*
G01X1190000D02*
X1191633Y-761667D01*
X1193500Y-760667D01*
X1194667Y-759001D01*
X1195133Y-756667D01*
X1194667Y-754334D01*
X1193267Y-752334D01*
X1191167Y-751333D01*
X1188833D01*
X1187433Y-750667D01*
X1186266Y-749000D01*
X1185800Y-746667D01*
X1186500Y-744333D01*
X1188133Y-742667D01*
X1190000Y-742000D01*
X1191866Y-742667D01*
X1193500Y-744333D01*
X1194200Y-746667D01*
X1193733Y-749000D01*
X1192567Y-750667D01*
X1191167Y-751333D01*
X1188833D01*
X1186733Y-752334D01*
X1185333Y-754334D01*
X1184867Y-756667D01*
X1185333Y-759001D01*
X1186500Y-760667D01*
X1188367Y-761667D01*
X1190000Y-762000D01*
G01X1209000D02*
X1210633Y-761667D01*
X1212500Y-760667D01*
X1213667Y-759001D01*
X1214133Y-756667D01*
X1213667Y-754334D01*
X1212267Y-752334D01*
X1210167Y-751333D01*
X1207833D01*
X1206433Y-750667D01*
X1205266Y-749000D01*
X1204800Y-746667D01*
X1205500Y-744333D01*
X1207133Y-742667D01*
X1209000Y-742000D01*
X1210866Y-742667D01*
X1212500Y-744333D01*
X1213200Y-746667D01*
X1212733Y-749000D01*
X1211567Y-750667D01*
X1210167Y-751333D01*
X1207833D01*
X1205733Y-752334D01*
X1204333Y-754334D01*
X1203867Y-756667D01*
X1204333Y-759001D01*
X1205500Y-760667D01*
X1207367Y-761667D01*
X1209000Y-762000D01*
G01X1227533D02*
X1228000Y-757667D01*
X1228700Y-754000D01*
X1229633Y-750667D01*
X1230800Y-747000D01*
X1232667Y-742000D01*
X1223333D01*
G01X1241867Y-759001D02*
X1243266Y-760667D01*
X1244900Y-761667D01*
X1247000Y-762000D01*
X1249100Y-761333D01*
X1250733Y-760000D01*
X1251900Y-757667D01*
X1252133Y-755000D01*
X1251667Y-752334D01*
X1250500Y-750667D01*
X1248866Y-749334D01*
X1247234Y-749000D01*
X1245600Y-749334D01*
X1243500Y-750667D01*
X1244200Y-742000D01*
X1250500D01*
G01X1265533Y-762000D02*
X1266000Y-757667D01*
X1266700Y-754000D01*
X1267633Y-750667D01*
X1268800Y-747000D01*
X1270667Y-742000D01*
X1261333D01*
G01X1279867Y-758000D02*
X1281266Y-760334D01*
X1283133Y-761667D01*
X1285234Y-762000D01*
X1287100Y-761667D01*
X1288967Y-760000D01*
X1290133Y-758000D01*
X1290367Y-756000D01*
X1289900Y-753667D01*
X1288267Y-752000D01*
X1286633Y-751333D01*
X1284533D01*
G01X1286633D02*
X1288033Y-750333D01*
X1289200Y-748667D01*
X1289667Y-746667D01*
X1289200Y-744667D01*
X1288033Y-743000D01*
X1285933Y-742000D01*
X1283833Y-742333D01*
X1281733Y-743667D01*
G01X1230000Y1250000D02*
Y1220000D01*
G01Y1275000D02*
Y1250000D01*
G01X1317980Y1249120D02*
Y1219120D01*
G01Y1274120D02*
Y1249120D01*
G01X1369166Y-760000D02*
X1375000Y-740000D01*
X1380834Y-760000D01*
G01X1378733Y-753000D02*
X1371266D01*
G54D21*
G01X-1536644Y69862D02*
G03X-1527785Y61004I8858J0D01*
G01X-1536644Y366909D02*
Y69862D01*
G01Y310807D02*
X-1229085D01*
G01X-1536644Y375768D02*
Y310807D01*
G01X-1530738Y372815D02*
X-1536644Y366909D01*
G01X-1480837Y372815D02*
X-1530738D01*
G01X-1229085Y375768D02*
X-1536644D01*
G01X-1527785Y61004D02*
X-963012D01*
G01X-1525636Y147218D02*
X-1497880D01*
G01X-1525636Y206274D02*
Y147218D01*
G01X-1512689Y157105D02*
X-1518189Y160955D01*
G01X-1519189Y159029D02*
X-1511689D01*
G01X-1512689Y160955D02*
X-1518189Y157105D01*
G01X-1515439Y156405D02*
Y161655D01*
G01X-1518015Y188956D02*
Y183581D01*
G01D02*
X-1517665Y182455D01*
G01D02*
X-1516965Y181706D01*
G01D02*
X-1516090Y181456D01*
G01D02*
X-1515215Y181706D01*
G01D02*
X-1514515Y182455D01*
G01D02*
X-1514165Y183581D01*
G01X-1497880Y206274D02*
X-1525636D01*
G01X-1517156Y229075D02*
G03X-1497077I10039J0D01*
G01X-1517156D02*
Y249910D01*
G01X-1497077D02*
G03X-1517156I-10039J14597D01*
G01X-1514165Y183581D02*
Y188956D01*
G01X-1510253Y187706D02*
X-1509728Y188456D01*
G01D02*
X-1509115Y188831D01*
G01D02*
X-1508415Y188956D01*
G01D02*
X-1507540Y188706D01*
G01D02*
X-1506928Y188081D01*
G01D02*
X-1506753Y187331D01*
G01D02*
X-1506840Y186581D01*
G01D02*
X-1507190Y185956D01*
G01D02*
X-1508940Y184706D01*
G01D02*
X-1509728Y183831D01*
G01D02*
X-1510253Y182580D01*
G01D02*
X-1510428Y181456D01*
G01D02*
X-1506753D01*
G01X-1497880Y147218D02*
Y206274D01*
G01X-1497077Y249910D02*
Y229075D01*
G01X-1484108Y340585D02*
X-1487958Y335085D01*
G01X-1486033Y334085D02*
Y341585D01*
G01X-1487958Y340585D02*
X-1484108Y335085D01*
G01X-1483408Y337835D02*
X-1488658D01*
G01X-1471388Y2539D02*
X-1353868D01*
G01X-1471388Y213957D02*
Y2539D01*
G01X-1353868Y213957D02*
X-1471388D01*
G01X-1474931Y312874D02*
Y366909D01*
G01Y312874D02*
G03X-1470797I2067J0D01*
G01Y366909D02*
Y312874D01*
G01X-1474931Y366909D02*
X-1480837Y372815D01*
G01X-1464892D02*
X-1470797Y366909D01*
G01X-1234990Y372815D02*
X-1464892D01*
G01X-1416598Y192914D02*
X-1416160Y192164D01*
G01D02*
X-1415635Y191664D01*
G01D02*
X-1415023Y191414D01*
G01D02*
X-1414323Y191664D01*
G01D02*
X-1413798Y192164D01*
G01D02*
X-1413273Y192914D01*
G01D02*
X-1413098Y193914D01*
G01D02*
Y198914D01*
G01X-1407348Y191414D02*
Y198914D01*
G01X-1408398Y191414D02*
X-1406298D01*
G01X-1407348Y198914D02*
X-1408398Y197414D01*
G01X-1359478Y70226D02*
Y77726D01*
G01X-1357553Y76726D02*
X-1361403Y71226D01*
G01Y76726D02*
X-1357553Y71226D01*
G01X-1356853Y73976D02*
X-1362103D01*
G01X-1365726Y339780D02*
Y334405D01*
G01D02*
X-1365376Y333279D01*
G01D02*
X-1364676Y332529D01*
G01D02*
X-1363801Y332280D01*
G01D02*
X-1362926Y332529D01*
G01D02*
X-1362226Y333279D01*
G01D02*
X-1361876Y334405D01*
G01D02*
Y339780D01*
G01X-1356301D02*
X-1357351Y338280D01*
G01Y332280D02*
X-1355251D01*
G01X-1353868Y2539D02*
Y213957D01*
G01X-1356301Y332280D02*
Y339780D01*
G01X-1319120Y155330D02*
X-1321370D01*
G01D02*
Y155830D01*
G01D02*
X-1321258Y155990D01*
G01D02*
X-1321108Y156090D01*
G01D02*
X-1320808Y156130D01*
G01D02*
X-1320508Y156090D01*
G01D02*
X-1320320Y155970D01*
G01D02*
X-1320208Y155830D01*
G01D02*
Y155330D01*
G01Y155830D02*
X-1319120Y156130D01*
G01Y157080D02*
X-1319158Y157220D01*
G01D02*
X-1319270Y157380D01*
G01D02*
X-1319458Y157480D01*
G01D02*
X-1319720Y157520D01*
G01D02*
X-1319983Y157480D01*
G01D02*
X-1320208Y157360D01*
G01D02*
X-1320320Y157180D01*
G01D02*
Y156980D01*
G01D02*
X-1320395Y156860D01*
G01D02*
X-1320583Y156760D01*
G01D02*
X-1320845Y156720D01*
G01D02*
X-1321108Y156780D01*
G01D02*
X-1321295Y156920D01*
G01D02*
X-1321370Y157080D01*
G01D02*
X-1321295Y157240D01*
G01D02*
X-1321108Y157380D01*
G01D02*
X-1320845Y157440D01*
G01D02*
X-1320583Y157400D01*
G01D02*
X-1320395Y157300D01*
G01D02*
X-1320320Y157180D01*
G01D02*
Y156980D01*
G01D02*
X-1320208Y156800D01*
G01D02*
X-1319983Y156680D01*
G01D02*
X-1319720Y156640D01*
G01D02*
X-1319458Y156680D01*
G01D02*
X-1319270Y156780D01*
G01D02*
X-1319158Y156940D01*
G01D02*
X-1319120Y157080D01*
G01X-1319458Y157990D02*
X-1319270Y158110D01*
G01D02*
X-1319158Y158250D01*
G01D02*
X-1319120Y158430D01*
G01D02*
X-1319195Y158610D01*
G01D02*
X-1319345Y158750D01*
G01D02*
X-1319608Y158850D01*
G01D02*
X-1319908Y158870D01*
G01D02*
X-1320208Y158830D01*
G01D02*
X-1320395Y158730D01*
G01D02*
X-1320545Y158590D01*
G01D02*
X-1320583Y158450D01*
G01D02*
X-1320545Y158310D01*
G01D02*
X-1320395Y158130D01*
G01D02*
X-1321370Y158190D01*
G01D02*
Y158730D01*
G01X-1316425Y149665D02*
X-1324178D01*
G01X-1316425Y164494D02*
Y149665D01*
G01X-1324178D02*
Y164494D01*
G01D02*
X-1316425D01*
G01X-1288566Y63795D02*
X-1225116D01*
G01X-1288566Y253095D02*
Y63795D01*
G01X-1280291Y85270D02*
X-1285791Y89120D01*
G01X-1280291D02*
X-1285791Y85270D01*
G01X-1283040Y84570D02*
Y89820D01*
G01X-1286791Y87195D02*
X-1279291D01*
G01X-1225116Y253095D02*
X-1288566D01*
G01X-1262281Y217043D02*
X-1261843Y216293D01*
G01D02*
X-1261318Y215793D01*
G01D02*
X-1260706Y215543D01*
G01D02*
X-1260006Y215793D01*
G01D02*
X-1259481Y216293D01*
G01D02*
X-1258956Y217043D01*
G01D02*
X-1258781Y218043D01*
G01D02*
Y223043D01*
G01X-1254693Y221793D02*
X-1254168Y222543D01*
G01D02*
X-1253556Y222918D01*
G01D02*
X-1252856Y223043D01*
G01D02*
X-1251981Y222793D01*
G01D02*
X-1251368Y222168D01*
G01D02*
X-1251193Y221418D01*
G01D02*
X-1251281Y220668D01*
G01D02*
X-1251631Y220043D01*
G01D02*
X-1253381Y218793D01*
G01D02*
X-1254168Y217918D01*
G01D02*
X-1254693Y216668D01*
G01D02*
X-1254868Y215543D01*
G01D02*
X-1251193D01*
G01X-1229085Y366909D02*
X-1234990Y372815D01*
G01X-1225116Y63795D02*
Y253095D01*
G01X-1229085Y319665D02*
Y366909D01*
G01Y319665D02*
G03X-1220226Y310807I8858J0D01*
G01X-1214321D02*
X-1220226D01*
G01X-1229085D02*
Y375768D01*
G01X-1214321Y310807D02*
G03X-1205463Y319665I0J8858D01*
G01Y355098D02*
Y319665D01*
G01X-1190699Y369862D02*
G03X-1205463Y355098I0J-14764D01*
G01X-1186447Y122776D02*
G03X-1166368I10039J0D01*
G01X-1186447D02*
Y143611D01*
G01X-1166368D02*
G03X-1186447I-10039J14597D01*
G01X966348Y369862D02*
X-1190699D01*
G01X-1166368Y143611D02*
Y122776D01*
G01X-1108581Y48425D02*
X-1093522D01*
G01X-1108581Y187973D02*
Y48425D01*
G01X-1045687Y187973D02*
X-1108581D01*
G01X-1093522Y-128149D02*
X-1060746D01*
G01X-1093522Y48425D02*
Y-128149D01*
G01X-1075209Y126982D02*
X-1079059Y121482D01*
G01X-1077134Y120482D02*
Y127982D01*
G01X-1079059Y126982D02*
X-1075209Y121482D01*
G01X-1074509Y124232D02*
X-1079759D01*
G01X-1078784Y167662D02*
X-1078346Y166912D01*
G01D02*
X-1077821Y166412D01*
G01D02*
X-1077209Y166162D01*
G01D02*
X-1076509Y166412D01*
G01D02*
X-1075984Y166912D01*
G01D02*
X-1075459Y167662D01*
G01D02*
X-1075284Y168662D01*
G01D02*
Y173662D01*
G01X-1060746Y-128149D02*
Y48425D01*
G01D02*
X-1045687D01*
G01X-1071459Y167662D02*
X-1070934Y166787D01*
G01D02*
X-1070234Y166287D01*
G01D02*
X-1069446Y166162D01*
G01D02*
X-1068746Y166287D01*
G01D02*
X-1068046Y166912D01*
G01D02*
X-1067609Y167662D01*
G01D02*
X-1067521Y168412D01*
G01D02*
X-1067696Y169287D01*
G01D02*
X-1068309Y169912D01*
G01D02*
X-1068921Y170162D01*
G01D02*
X-1069709D01*
G01X-1068921D02*
X-1068396Y170537D01*
G01D02*
X-1067959Y171162D01*
G01D02*
X-1067784Y171912D01*
G01D02*
X-1067959Y172662D01*
G01D02*
X-1068396Y173287D01*
G01D02*
X-1069184Y173662D01*
G01D02*
X-1069971Y173537D01*
G01D02*
X-1070759Y173037D01*
G01X-1044803Y9331D02*
X-974823D01*
G01X-1044803Y182362D02*
Y9331D01*
G01X-1045687Y48425D02*
Y187973D01*
G01X-974823Y182362D02*
X-1044803D01*
G01X-1041796Y224746D02*
X-1041956D01*
G01D02*
X-1042136Y224634D01*
G01D02*
X-1042276Y224446D01*
G01D02*
X-1042376Y224221D01*
G01D02*
X-1042456Y223846D01*
G01D02*
X-1042476Y223509D01*
G01D02*
X-1042436Y223171D01*
G01D02*
X-1042376Y222946D01*
G01D02*
X-1042256Y222721D01*
G01D02*
X-1042116Y222571D01*
G01D02*
X-1041976Y222496D01*
G01D02*
X-1041836D01*
G01X-1047203Y226506D02*
Y220553D01*
G01X-1035400Y226506D02*
X-1047203D01*
G01Y220553D02*
X-1035400D01*
G01X-1047953Y230903D02*
Y238656D01*
G01X-1033150Y230903D02*
X-1047953D01*
G01Y238656D02*
X-1033150D01*
G01X-1035360Y146384D02*
X-1031510Y151884D01*
G01X-1033435Y152884D02*
Y145384D01*
G01X-1031510Y146384D02*
X-1035360Y151884D01*
G01X-1036060Y149134D02*
X-1030810D01*
G01X-1028120Y209603D02*
X-1022167D01*
G01X-1028120Y221405D02*
Y209603D01*
G01X-1041536Y224559D02*
X-1041656Y224671D01*
G01D02*
X-1041796Y224746D01*
G01X-1041836Y222496D02*
X-1041696Y222571D01*
G01D02*
X-1041576Y222684D01*
G01D02*
X-1041476Y222833D01*
G01X-1041066Y222946D02*
X-1040946Y222684D01*
G01D02*
X-1040786Y222534D01*
G01D02*
X-1040606Y222496D01*
G01D02*
X-1040446Y222534D01*
G01D02*
X-1040286Y222721D01*
G01D02*
X-1040186Y222946D01*
G01D02*
X-1040166Y223171D01*
G01D02*
X-1040206Y223434D01*
G01D02*
X-1040346Y223621D01*
G01D02*
X-1040486Y223696D01*
G01D02*
X-1040666D01*
G01X-1040486D02*
X-1040366Y223809D01*
G01D02*
X-1040266Y223996D01*
G01D02*
X-1040226Y224221D01*
G01D02*
X-1040266Y224446D01*
G01D02*
X-1040366Y224634D01*
G01D02*
X-1040546Y224746D01*
G01D02*
X-1040726Y224709D01*
G01D02*
X-1040906Y224559D01*
G01X-1035400Y220553D02*
Y226506D01*
G01X-1026173Y215269D02*
X-1026285Y215149D01*
G01D02*
X-1026360Y215009D01*
G01D02*
Y214849D01*
G01D02*
X-1026248Y214669D01*
G01D02*
X-1026060Y214529D01*
G01X-1024110Y216419D02*
X-1026360D01*
G01D02*
X-1024748Y215679D01*
G01X-1022167Y221405D02*
X-1028120D01*
G01X-1040786Y235661D02*
X-1040906Y235773D01*
G01D02*
X-1041046Y235848D01*
G01D02*
X-1041206D01*
G01D02*
X-1041386Y235736D01*
G01D02*
X-1041526Y235548D01*
G01D02*
X-1041626Y235323D01*
G01D02*
X-1041706Y234948D01*
G01D02*
X-1041726Y234611D01*
G01D02*
X-1041686Y234273D01*
G01D02*
X-1041626Y234048D01*
G01D02*
X-1041506Y233823D01*
G01D02*
X-1041366Y233673D01*
G01D02*
X-1041226Y233598D01*
G01D02*
X-1041086D01*
G01D02*
X-1040946Y233673D01*
G01D02*
X-1040826Y233786D01*
G01D02*
X-1040726Y233936D01*
G01X-1040256Y235473D02*
X-1040136Y235698D01*
G01D02*
X-1039996Y235811D01*
G01D02*
X-1039836Y235848D01*
G01D02*
X-1039636Y235773D01*
G01D02*
X-1039496Y235586D01*
G01D02*
X-1039456Y235361D01*
G01D02*
X-1039476Y235136D01*
G01D02*
X-1039556Y234948D01*
G01D02*
X-1039956Y234573D01*
G01D02*
X-1040136Y234311D01*
G01D02*
X-1040256Y233936D01*
G01D02*
X-1040296Y233598D01*
G01D02*
X-1039456D01*
G01X-1033150Y238656D02*
Y230903D01*
G01X-1034144Y304754D02*
X-1019144D01*
G01X-1034144Y334754D02*
Y304754D01*
G01X-1023884Y310329D02*
X-1029384Y314179D01*
G01X-1030384Y312254D02*
X-1022884D01*
G01X-1023884Y314179D02*
X-1029384Y310329D01*
G01X-1026634Y309629D02*
Y314879D01*
G01X-1025972Y319450D02*
X-1026672Y319575D01*
G01D02*
X-1030172D01*
G01X-1029297Y322237D02*
X-1029822Y322612D01*
G01D02*
X-1030085Y323050D01*
G01X-1027197Y323175D02*
X-1026584Y322612D01*
G01D02*
X-1025709Y322237D01*
G01X-1030085Y323050D02*
X-1030172Y323550D01*
G01D02*
X-1029997Y324175D01*
G01D02*
X-1029559Y324612D01*
G01D02*
X-1029035Y324737D01*
G01D02*
X-1028509Y324675D01*
G01D02*
X-1028072Y324425D01*
G01D02*
X-1027197Y323175D01*
G01X-1027109Y327337D02*
X-1027722Y327775D01*
G01D02*
X-1028072Y328150D01*
G01D02*
X-1028247Y328650D01*
G01D02*
X-1028072Y329087D01*
G01D02*
X-1027722Y329400D01*
G01D02*
X-1027197Y329650D01*
G01D02*
X-1026584Y329712D01*
G01D02*
X-1026059Y329650D01*
G01X-1025622Y327650D02*
X-1026409Y327400D01*
G01D02*
X-1027284Y327337D01*
G01D02*
X-1028422Y327462D01*
G01D02*
X-1029035Y327650D01*
G01D02*
X-1029647Y327962D01*
G01D02*
X-1030085Y328400D01*
G01D02*
X-1030172Y328837D01*
G01D02*
X-1029997Y329275D01*
G01D02*
X-1029559Y329587D01*
G01X-1019144Y334754D02*
X-1034144D01*
G01X-1035963Y347254D02*
X-1038213D01*
G01D02*
Y347754D01*
G01D02*
X-1038100Y347914D01*
G01D02*
X-1037950Y348014D01*
G01D02*
X-1037650Y348054D01*
G01D02*
X-1037350Y348014D01*
G01D02*
X-1037163Y347894D01*
G01D02*
X-1037050Y347754D01*
G01D02*
Y347254D01*
G01Y347754D02*
X-1035963Y348054D01*
G01Y349004D02*
X-1038213D01*
G01D02*
X-1037763Y348764D01*
G01X-1035963D02*
Y349244D01*
G01Y350354D02*
X-1038213D01*
G01D02*
X-1037763Y350114D01*
G01X-1035963D02*
Y350594D01*
G01X-1033267Y341589D02*
X-1041020D01*
G01X-1033267Y356419D02*
Y341589D01*
G01X-1041020D02*
Y356419D01*
G01X-1027713Y347254D02*
X-1029963D01*
G01D02*
Y347754D01*
G01D02*
X-1029850Y347914D01*
G01D02*
X-1029700Y348014D01*
G01D02*
X-1029400Y348054D01*
G01D02*
X-1029100Y348014D01*
G01D02*
X-1028913Y347894D01*
G01D02*
X-1028800Y347754D01*
G01D02*
Y347254D01*
G01Y347754D02*
X-1027713Y348054D01*
G01Y349004D02*
X-1029963D01*
G01D02*
X-1029513Y348764D01*
G01X-1027713D02*
Y349244D01*
G01X-1029963Y350354D02*
X-1029888Y350194D01*
G01D02*
X-1029700Y350074D01*
G01D02*
X-1029475Y349994D01*
G01D02*
X-1029175Y349934D01*
G01D02*
X-1028838Y349914D01*
G01D02*
X-1028500Y349934D01*
G01D02*
X-1028200Y349994D01*
G01D02*
X-1027975Y350074D01*
G01D02*
X-1027788Y350194D01*
G01D02*
X-1027713Y350354D01*
G01D02*
X-1027788Y350514D01*
G01D02*
X-1027975Y350634D01*
G01D02*
X-1028200Y350714D01*
G01D02*
X-1028500Y350774D01*
G01D02*
X-1028838Y350794D01*
G01D02*
X-1029175Y350774D01*
G01D02*
X-1029475Y350714D01*
G01D02*
X-1029700Y350634D01*
G01D02*
X-1029888Y350514D01*
G01D02*
X-1029963Y350354D01*
G01X-1025017Y341589D02*
X-1032770D01*
G01D02*
Y356419D01*
G01X-1041020D02*
X-1033267D01*
G01X-1032770D02*
X-1025017D01*
G01X-1015313Y162898D02*
X-1014876Y162147D01*
G01D02*
X-1014351Y161648D01*
G01D02*
X-1013738Y161398D01*
G01D02*
X-1013038Y161648D01*
G01D02*
X-1012513Y162147D01*
G01D02*
X-1011988Y162898D01*
G01D02*
X-1011813Y163898D01*
G01D02*
Y168898D01*
G01X-1022167Y209603D02*
Y221405D01*
G01X-1013017Y208853D02*
X-1020770D01*
G01X-1013017Y223655D02*
Y208853D01*
G01X-1020770D02*
Y223655D01*
G01X-1026060Y214529D02*
X-1025835Y214429D01*
G01D02*
X-1025460Y214349D01*
G01D02*
X-1025123Y214329D01*
G01D02*
X-1024785Y214369D01*
G01D02*
X-1024560Y214429D01*
G01D02*
X-1024335Y214549D01*
G01D02*
X-1024185Y214689D01*
G01D02*
X-1024110Y214829D01*
G01D02*
Y214969D01*
G01D02*
X-1024185Y215109D01*
G01D02*
X-1024298Y215229D01*
G01D02*
X-1024448Y215329D01*
G01X-1024748Y215679D02*
Y216679D01*
G01X-1017775Y216019D02*
X-1017888Y215899D01*
G01D02*
X-1017963Y215759D01*
G01D02*
Y215599D01*
G01D02*
X-1017850Y215419D01*
G01D02*
X-1017663Y215279D01*
G01D02*
X-1017438Y215179D01*
G01D02*
X-1017063Y215099D01*
G01D02*
X-1016725Y215079D01*
G01D02*
X-1016388Y215119D01*
G01D02*
X-1016163Y215179D01*
G01D02*
X-1015938Y215299D01*
G01D02*
X-1015788Y215439D01*
G01D02*
X-1015713Y215579D01*
G01D02*
Y215719D01*
G01D02*
X-1015788Y215859D01*
G01D02*
X-1015900Y215979D01*
G01D02*
X-1016050Y216079D01*
G01X-1015713Y216929D02*
X-1017963D01*
G01D02*
X-1017513Y216689D01*
G01X-1015713D02*
Y217169D01*
G01X-1020770Y223655D02*
X-1013017D01*
G01X-1014475Y234115D02*
X-1022228D01*
G01X-1014475Y248944D02*
Y234115D01*
G01X-1022228D02*
Y248944D01*
G01X-1017170Y239780D02*
X-1019420D01*
G01D02*
Y240280D01*
G01D02*
X-1019308Y240440D01*
G01D02*
X-1019158Y240540D01*
G01D02*
X-1018858Y240580D01*
G01D02*
X-1018558Y240540D01*
G01D02*
X-1018370Y240420D01*
G01D02*
X-1018258Y240280D01*
G01D02*
Y239780D01*
G01Y240280D02*
X-1017170Y240580D01*
G01Y241530D02*
X-1017208Y241670D01*
G01D02*
X-1017320Y241830D01*
G01D02*
X-1017508Y241930D01*
G01D02*
X-1017770Y241970D01*
G01D02*
X-1018033Y241930D01*
G01D02*
X-1018258Y241810D01*
G01D02*
X-1018370Y241630D01*
G01D02*
Y241430D01*
G01D02*
X-1018445Y241310D01*
G01D02*
X-1018633Y241210D01*
G01D02*
X-1018895Y241170D01*
G01D02*
X-1019158Y241230D01*
G01D02*
X-1019345Y241370D01*
G01D02*
X-1019420Y241530D01*
G01D02*
X-1019345Y241690D01*
G01D02*
X-1019158Y241830D01*
G01D02*
X-1018895Y241890D01*
G01D02*
X-1018633Y241850D01*
G01D02*
X-1018445Y241750D01*
G01D02*
X-1018370Y241630D01*
G01D02*
Y241430D01*
G01D02*
X-1018258Y241250D01*
G01D02*
X-1018033Y241130D01*
G01D02*
X-1017770Y241090D01*
G01D02*
X-1017508Y241130D01*
G01D02*
X-1017320Y241230D01*
G01D02*
X-1017208Y241390D01*
G01D02*
X-1017170Y241530D01*
G01Y243120D02*
X-1019420D01*
G01D02*
X-1017808Y242380D01*
G01D02*
Y243380D01*
G01X-1022228Y248944D02*
X-1014475D01*
G01X-1019144Y304754D02*
Y334754D01*
G01X-1025972Y317075D02*
X-1025447Y317387D01*
G01D02*
X-1025097Y317762D01*
G01D02*
X-1024922Y318200D01*
G01D02*
X-1025097Y318700D01*
G01D02*
X-1025447Y319075D01*
G01D02*
X-1025972Y319450D01*
G01X-1025709Y322237D02*
X-1024922Y322112D01*
G01D02*
Y324737D01*
G01X-1026059Y329650D02*
X-1025534Y329400D01*
G01D02*
X-1025097Y329025D01*
G01D02*
X-1024922Y328587D01*
G01D02*
X-1025097Y328087D01*
G01D02*
X-1025622Y327650D01*
G01X-1025017Y356419D02*
Y341589D01*
G01X-1005013Y161398D02*
Y168898D01*
G01D02*
X-1008251Y163523D01*
G01D02*
X-1003876D01*
G01X-1006716Y225606D02*
X-991886D01*
G01X-1006716Y217853D02*
Y225606D01*
G01X-991886Y217853D02*
X-1006716D01*
G01Y226103D02*
Y233856D01*
G01X-991886Y226103D02*
X-1006716D01*
G01X-1000376Y221411D02*
Y223661D01*
G01D02*
X-999876D01*
G01D02*
X-999716Y223548D01*
G01D02*
X-999616Y223398D01*
G01D02*
X-999576Y223098D01*
G01D02*
X-999616Y222798D01*
G01D02*
X-999736Y222611D01*
G01D02*
X-999876Y222498D01*
G01D02*
X-1000376D01*
G01X-999876D02*
X-999576Y221411D01*
G01X-998666D02*
X-998626Y221898D01*
G01D02*
X-998566Y222311D01*
G01D02*
X-998486Y222686D01*
G01D02*
X-998386Y223098D01*
G01D02*
X-998226Y223661D01*
G01D02*
X-999026D01*
G01X-1006716Y234353D02*
Y242106D01*
G01X-991886Y234353D02*
X-1006716D01*
G01Y233856D02*
X-991886D01*
G01X-1006716Y242106D02*
X-991886D01*
G01X-1006716Y242603D02*
Y250356D01*
G01X-991886Y242603D02*
X-1006716D01*
G01X-1000376Y228798D02*
Y231048D01*
G01D02*
X-999876D01*
G01D02*
X-999716Y230936D01*
G01D02*
X-999616Y230786D01*
G01D02*
X-999576Y230486D01*
G01D02*
X-999616Y230186D01*
G01D02*
X-999736Y229998D01*
G01D02*
X-999876Y229886D01*
G01D02*
X-1000376D01*
G01X-999876D02*
X-999576Y228798D01*
G01X-999006Y229736D02*
X-998866Y229998D01*
G01D02*
X-998746Y230148D01*
G01D02*
X-998586Y230223D01*
G01D02*
X-998446Y230148D01*
G01D02*
X-998346Y229998D01*
G01D02*
X-998266Y229773D01*
G01D02*
X-998246Y229511D01*
G01D02*
X-998266Y229286D01*
G01D02*
X-998346Y229061D01*
G01D02*
X-998466Y228873D01*
G01D02*
X-998606Y228798D01*
G01D02*
X-998766Y228873D01*
G01D02*
X-998906Y229098D01*
G01D02*
X-998986Y229436D01*
G01D02*
X-999006Y229811D01*
G01D02*
X-998966Y230298D01*
G01D02*
X-998906Y230561D01*
G01D02*
X-998806Y230823D01*
G01D02*
X-998666Y231011D01*
G01D02*
X-998526Y231048D01*
G01D02*
X-998386Y230973D01*
G01D02*
X-998286Y230786D01*
G01X-1001051Y237911D02*
Y240161D01*
G01D02*
X-1000551D01*
G01D02*
X-1000391Y240048D01*
G01D02*
X-1000291Y239898D01*
G01D02*
X-1000251Y239598D01*
G01D02*
X-1000291Y239298D01*
G01D02*
X-1000411Y239111D01*
G01D02*
X-1000551Y238998D01*
G01D02*
X-1001051D01*
G01X-1000551D02*
X-1000251Y237911D01*
G01X-999341D02*
X-999301Y238398D01*
G01D02*
X-999241Y238811D01*
G01D02*
X-999161Y239186D01*
G01D02*
X-999061Y239598D01*
G01D02*
X-998901Y240161D01*
G01D02*
X-999701D01*
G01X-998391Y238248D02*
X-998271Y238061D01*
G01D02*
X-998131Y237948D01*
G01D02*
X-997951Y237911D01*
G01D02*
X-997771Y237986D01*
G01D02*
X-997631Y238136D01*
G01D02*
X-997531Y238398D01*
G01D02*
X-997511Y238698D01*
G01D02*
X-997551Y238998D01*
G01D02*
X-997651Y239186D01*
G01D02*
X-997791Y239336D01*
G01D02*
X-997931Y239373D01*
G01D02*
X-998071Y239336D01*
G01D02*
X-998251Y239186D01*
G01D02*
X-998191Y240161D01*
G01D02*
X-997651D01*
G01X-1006716Y250356D02*
X-991886D01*
G01X-1006716Y250853D02*
Y258606D01*
G01X-991886Y250853D02*
X-1006716D01*
G01Y259103D02*
Y266856D01*
G01X-991886Y259103D02*
X-1006716D01*
G01Y258606D02*
X-991886D01*
G01X-1001051Y245298D02*
Y247548D01*
G01D02*
X-1000551D01*
G01D02*
X-1000391Y247436D01*
G01D02*
X-1000291Y247286D01*
G01D02*
X-1000251Y246986D01*
G01D02*
X-1000291Y246686D01*
G01D02*
X-1000411Y246498D01*
G01D02*
X-1000551Y246386D01*
G01D02*
X-1001051D01*
G01X-1000551D02*
X-1000251Y245298D01*
G01X-999301D02*
X-999161Y245336D01*
G01D02*
X-999001Y245448D01*
G01D02*
X-998901Y245636D01*
G01D02*
X-998861Y245898D01*
G01D02*
X-998901Y246161D01*
G01D02*
X-999021Y246386D01*
G01D02*
X-999201Y246498D01*
G01D02*
X-999401D01*
G01D02*
X-999521Y246573D01*
G01D02*
X-999621Y246761D01*
G01D02*
X-999661Y247023D01*
G01D02*
X-999601Y247286D01*
G01D02*
X-999461Y247473D01*
G01D02*
X-999301Y247548D01*
G01D02*
X-999141Y247473D01*
G01D02*
X-999001Y247286D01*
G01D02*
X-998941Y247023D01*
G01D02*
X-998981Y246761D01*
G01D02*
X-999081Y246573D01*
G01D02*
X-999201Y246498D01*
G01D02*
X-999401D01*
G01D02*
X-999581Y246386D01*
G01D02*
X-999701Y246161D01*
G01D02*
X-999741Y245898D01*
G01D02*
X-999701Y245636D01*
G01D02*
X-999601Y245448D01*
G01D02*
X-999441Y245336D01*
G01D02*
X-999301Y245298D01*
G01X-997951D02*
Y247548D01*
G01D02*
X-998191Y247098D01*
G01Y245298D02*
X-997711D01*
G01X-1001051Y253548D02*
Y255798D01*
G01D02*
X-1000551D01*
G01D02*
X-1000391Y255686D01*
G01D02*
X-1000291Y255536D01*
G01D02*
X-1000251Y255236D01*
G01D02*
X-1000291Y254936D01*
G01D02*
X-1000411Y254748D01*
G01D02*
X-1000551Y254636D01*
G01D02*
X-1001051D01*
G01X-1000551D02*
X-1000251Y253548D01*
G01X-999301D02*
X-999161Y253586D01*
G01D02*
X-999001Y253698D01*
G01D02*
X-998901Y253886D01*
G01D02*
X-998861Y254148D01*
G01D02*
X-998901Y254411D01*
G01D02*
X-999021Y254636D01*
G01D02*
X-999201Y254748D01*
G01D02*
X-999401D01*
G01D02*
X-999521Y254823D01*
G01D02*
X-999621Y255011D01*
G01D02*
X-999661Y255273D01*
G01D02*
X-999601Y255536D01*
G01D02*
X-999461Y255723D01*
G01D02*
X-999301Y255798D01*
G01D02*
X-999141Y255723D01*
G01D02*
X-999001Y255536D01*
G01D02*
X-998941Y255273D01*
G01D02*
X-998981Y255011D01*
G01D02*
X-999081Y254823D01*
G01D02*
X-999201Y254748D01*
G01D02*
X-999401D01*
G01D02*
X-999581Y254636D01*
G01D02*
X-999701Y254411D01*
G01D02*
X-999741Y254148D01*
G01D02*
X-999701Y253886D01*
G01D02*
X-999601Y253698D01*
G01D02*
X-999441Y253586D01*
G01D02*
X-999301Y253548D01*
G01X-998331Y255423D02*
X-998211Y255648D01*
G01D02*
X-998071Y255761D01*
G01D02*
X-997911Y255798D01*
G01D02*
X-997711Y255723D01*
G01D02*
X-997571Y255536D01*
G01D02*
X-997531Y255311D01*
G01D02*
X-997551Y255086D01*
G01D02*
X-997631Y254898D01*
G01D02*
X-998031Y254523D01*
G01D02*
X-998211Y254261D01*
G01D02*
X-998331Y253886D01*
G01D02*
X-998371Y253548D01*
G01D02*
X-997531D01*
G01X-1006716Y275106D02*
X-991886D01*
G01X-1006716Y267353D02*
Y275106D01*
G01X-991886Y267353D02*
X-1006716D01*
G01Y266856D02*
X-991886D01*
G01X-1001051Y270911D02*
Y273161D01*
G01D02*
X-1000551D01*
G01D02*
X-1000391Y273048D01*
G01D02*
X-1000291Y272898D01*
G01D02*
X-1000251Y272598D01*
G01D02*
X-1000291Y272298D01*
G01D02*
X-1000411Y272111D01*
G01D02*
X-1000551Y271998D01*
G01D02*
X-1001051D01*
G01X-1000551D02*
X-1000251Y270911D01*
G01X-999341D02*
X-999301Y271398D01*
G01D02*
X-999241Y271811D01*
G01D02*
X-999161Y272186D01*
G01D02*
X-999061Y272598D01*
G01D02*
X-998901Y273161D01*
G01D02*
X-999701D01*
G01X-997991Y270911D02*
X-997951Y271398D01*
G01D02*
X-997891Y271811D01*
G01D02*
X-997811Y272186D01*
G01D02*
X-997711Y272598D01*
G01D02*
X-997551Y273161D01*
G01D02*
X-998351D01*
G01X-1001051Y261798D02*
Y264048D01*
G01D02*
X-1000551D01*
G01D02*
X-1000391Y263936D01*
G01D02*
X-1000291Y263786D01*
G01D02*
X-1000251Y263486D01*
G01D02*
X-1000291Y263186D01*
G01D02*
X-1000411Y262998D01*
G01D02*
X-1000551Y262886D01*
G01D02*
X-1001051D01*
G01X-1000551D02*
X-1000251Y261798D01*
G01X-999341D02*
X-999301Y262286D01*
G01D02*
X-999241Y262698D01*
G01D02*
X-999161Y263073D01*
G01D02*
X-999061Y263486D01*
G01D02*
X-998901Y264048D01*
G01D02*
X-999701D01*
G01X-998331Y262736D02*
X-998191Y262998D01*
G01D02*
X-998071Y263148D01*
G01D02*
X-997911Y263223D01*
G01D02*
X-997771Y263148D01*
G01D02*
X-997671Y262998D01*
G01D02*
X-997591Y262773D01*
G01D02*
X-997571Y262511D01*
G01D02*
X-997591Y262286D01*
G01D02*
X-997671Y262061D01*
G01D02*
X-997791Y261873D01*
G01D02*
X-997931Y261798D01*
G01D02*
X-998091Y261873D01*
G01D02*
X-998231Y262098D01*
G01D02*
X-998311Y262436D01*
G01D02*
X-998331Y262811D01*
G01D02*
X-998291Y263298D01*
G01D02*
X-998231Y263561D01*
G01D02*
X-998131Y263823D01*
G01D02*
X-997991Y264011D01*
G01D02*
X-997851Y264048D01*
G01D02*
X-997711Y263973D01*
G01D02*
X-997611Y263786D01*
G01X-1006716Y275603D02*
Y283356D01*
G01X-991886Y275603D02*
X-1006716D01*
G01Y283853D02*
Y291606D01*
G01X-991886Y283853D02*
X-1006716D01*
G01Y283356D02*
X-991886D01*
G01X-1001051Y278298D02*
Y280548D01*
G01D02*
X-1000551D01*
G01D02*
X-1000391Y280436D01*
G01D02*
X-1000291Y280286D01*
G01D02*
X-1000251Y279986D01*
G01D02*
X-1000291Y279686D01*
G01D02*
X-1000411Y279498D01*
G01D02*
X-1000551Y279386D01*
G01D02*
X-1001051D01*
G01X-1000551D02*
X-1000251Y278298D01*
G01X-999301D02*
X-999161Y278336D01*
G01D02*
X-999001Y278448D01*
G01D02*
X-998901Y278636D01*
G01D02*
X-998861Y278898D01*
G01D02*
X-998901Y279161D01*
G01D02*
X-999021Y279386D01*
G01D02*
X-999201Y279498D01*
G01D02*
X-999401D01*
G01D02*
X-999521Y279573D01*
G01D02*
X-999621Y279761D01*
G01D02*
X-999661Y280023D01*
G01D02*
X-999601Y280286D01*
G01D02*
X-999461Y280473D01*
G01D02*
X-999301Y280548D01*
G01D02*
X-999141Y280473D01*
G01D02*
X-999001Y280286D01*
G01D02*
X-998941Y280023D01*
G01D02*
X-998981Y279761D01*
G01D02*
X-999081Y279573D01*
G01D02*
X-999201Y279498D01*
G01D02*
X-999401D01*
G01D02*
X-999581Y279386D01*
G01D02*
X-999701Y279161D01*
G01D02*
X-999741Y278898D01*
G01D02*
X-999701Y278636D01*
G01D02*
X-999601Y278448D01*
G01D02*
X-999441Y278336D01*
G01D02*
X-999301Y278298D01*
G01X-998391Y278748D02*
X-998271Y278486D01*
G01D02*
X-998111Y278336D01*
G01D02*
X-997931Y278298D01*
G01D02*
X-997771Y278336D01*
G01D02*
X-997611Y278523D01*
G01D02*
X-997511Y278748D01*
G01D02*
X-997491Y278973D01*
G01D02*
X-997531Y279236D01*
G01D02*
X-997671Y279423D01*
G01D02*
X-997811Y279498D01*
G01D02*
X-997991D01*
G01X-997811D02*
X-997691Y279611D01*
G01D02*
X-997591Y279798D01*
G01D02*
X-997551Y280023D01*
G01D02*
X-997591Y280248D01*
G01D02*
X-997691Y280436D01*
G01D02*
X-997871Y280548D01*
G01D02*
X-998051Y280511D01*
G01D02*
X-998231Y280361D01*
G01X-1001051Y286548D02*
Y288798D01*
G01D02*
X-1000551D01*
G01D02*
X-1000391Y288686D01*
G01D02*
X-1000291Y288536D01*
G01D02*
X-1000251Y288236D01*
G01D02*
X-1000291Y287936D01*
G01D02*
X-1000411Y287748D01*
G01D02*
X-1000551Y287636D01*
G01D02*
X-1001051D01*
G01X-1000551D02*
X-1000251Y286548D01*
G01X-999341D02*
X-999301Y287036D01*
G01D02*
X-999241Y287448D01*
G01D02*
X-999161Y287823D01*
G01D02*
X-999061Y288236D01*
G01D02*
X-998901Y288798D01*
G01D02*
X-999701D01*
G01X-997951Y286548D02*
X-997811Y286586D01*
G01D02*
X-997651Y286698D01*
G01D02*
X-997551Y286886D01*
G01D02*
X-997511Y287148D01*
G01D02*
X-997551Y287411D01*
G01D02*
X-997671Y287636D01*
G01D02*
X-997851Y287748D01*
G01D02*
X-998051D01*
G01D02*
X-998171Y287823D01*
G01D02*
X-998271Y288011D01*
G01D02*
X-998311Y288273D01*
G01D02*
X-998251Y288536D01*
G01D02*
X-998111Y288723D01*
G01D02*
X-997951Y288798D01*
G01D02*
X-997791Y288723D01*
G01D02*
X-997651Y288536D01*
G01D02*
X-997591Y288273D01*
G01D02*
X-997631Y288011D01*
G01D02*
X-997731Y287823D01*
G01D02*
X-997851Y287748D01*
G01D02*
X-998051D01*
G01D02*
X-998231Y287636D01*
G01D02*
X-998351Y287411D01*
G01D02*
X-998391Y287148D01*
G01D02*
X-998351Y286886D01*
G01D02*
X-998251Y286698D01*
G01D02*
X-998091Y286586D01*
G01D02*
X-997951Y286548D01*
G01X-1009801Y304530D02*
X-994801D01*
G01X-1009801Y334530D02*
Y304530D01*
G01X-1006716Y292103D02*
Y299856D01*
G01X-991886Y292103D02*
X-1006716D01*
G01Y299856D02*
X-991886D01*
G01X-1006716Y291606D02*
X-991886D01*
G01X-994801Y304530D02*
Y334530D01*
G01X-1001051Y294030D02*
Y296280D01*
G01D02*
X-1000551D01*
G01D02*
X-1000391Y296167D01*
G01D02*
X-1000291Y296017D01*
G01D02*
X-1000251Y295717D01*
G01D02*
X-1000291Y295417D01*
G01D02*
X-1000411Y295230D01*
G01D02*
X-1000551Y295117D01*
G01D02*
X-1001051D01*
G01X-1000551D02*
X-1000251Y294030D01*
G01X-999341D02*
X-999301Y294517D01*
G01D02*
X-999241Y294929D01*
G01D02*
X-999161Y295305D01*
G01D02*
X-999061Y295717D01*
G01D02*
X-998901Y296280D01*
G01D02*
X-999701D01*
G01X-998291Y294292D02*
X-998151Y294105D01*
G01D02*
X-997991Y294030D01*
G01D02*
X-997831Y294105D01*
G01D02*
X-997691Y294329D01*
G01D02*
X-997591Y294667D01*
G01D02*
X-997551Y295005D01*
G01D02*
Y295417D01*
G01D02*
X-997591Y295754D01*
G01D02*
X-997691Y296055D01*
G01D02*
X-997811Y296205D01*
G01D02*
X-997951Y296280D01*
G01D02*
X-998111Y296205D01*
G01D02*
X-998231Y296055D01*
G01D02*
X-998311Y295830D01*
G01D02*
X-998351Y295529D01*
G01D02*
X-998311Y295267D01*
G01D02*
X-998211Y295005D01*
G01D02*
X-998091Y294854D01*
G01D02*
X-997951Y294817D01*
G01D02*
X-997791Y294892D01*
G01D02*
X-997671Y295080D01*
G01D02*
X-997551Y295417D01*
G01X-999541Y310105D02*
X-1005041Y313955D01*
G01X-1006041Y312029D02*
X-998541D01*
G01X-999541Y313955D02*
X-1005041Y310105D01*
G01X-1002291Y309405D02*
Y314655D01*
G01X-1001036Y316570D02*
X-1000511Y316882D01*
G01D02*
X-1000161Y317257D01*
G01D02*
X-999986Y317695D01*
G01D02*
X-1000161Y318195D01*
G01D02*
X-1000511Y318570D01*
G01D02*
X-1001036Y318945D01*
G01D02*
X-1001736Y319070D01*
G01D02*
X-1005236D01*
G01X-1004361Y321732D02*
X-1004886Y322107D01*
G01D02*
X-1005148Y322545D01*
G01D02*
X-1005236Y323045D01*
G01X-1003136Y323920D02*
X-1002261Y322670D01*
G01D02*
X-1001648Y322107D01*
G01D02*
X-1000773Y321732D01*
G01D02*
X-999986Y321607D01*
G01D02*
Y324232D01*
G01X-994801Y334530D02*
X-1009801D01*
G01X-1005236Y323045D02*
X-1005061Y323670D01*
G01D02*
X-1004623Y324108D01*
G01D02*
X-1004098Y324232D01*
G01D02*
X-1003573Y324170D01*
G01D02*
X-1003136Y323920D01*
G01X-1000773Y326645D02*
X-1000336Y327020D01*
G01D02*
X-1000073Y327457D01*
G01D02*
X-999986Y328020D01*
G01D02*
X-1000161Y328583D01*
G01D02*
X-1000511Y329020D01*
G01D02*
X-1001123Y329332D01*
G01D02*
X-1001823Y329395D01*
G01D02*
X-1002523Y329270D01*
G01D02*
X-1002961Y328957D01*
G01D02*
X-1003311Y328520D01*
G01D02*
X-1003398Y328083D01*
G01D02*
X-1003311Y327645D01*
G01D02*
X-1002961Y327082D01*
G01D02*
X-1005236Y327270D01*
G01D02*
Y328957D01*
G01X-1001017Y340839D02*
X-1008770D01*
G01D02*
Y355669D01*
G01X-1003713Y347179D02*
X-1005963D01*
G01D02*
Y347679D01*
G01D02*
X-1005850Y347839D01*
G01D02*
X-1005700Y347939D01*
G01D02*
X-1005400Y347979D01*
G01D02*
X-1005100Y347939D01*
G01D02*
X-1004913Y347819D01*
G01D02*
X-1004800Y347679D01*
G01D02*
Y347179D01*
G01Y347679D02*
X-1003713Y347979D01*
G01X-1003975Y348589D02*
X-1003788Y348729D01*
G01D02*
X-1003713Y348889D01*
G01D02*
X-1003788Y349049D01*
G01D02*
X-1004013Y349189D01*
G01D02*
X-1004350Y349289D01*
G01D02*
X-1004688Y349329D01*
G01D02*
X-1005100D01*
G01D02*
X-1005438Y349289D01*
G01D02*
X-1005738Y349189D01*
G01D02*
X-1005888Y349069D01*
G01D02*
X-1005963Y348929D01*
G01D02*
X-1005888Y348769D01*
G01D02*
X-1005738Y348649D01*
G01D02*
X-1005513Y348569D01*
G01D02*
X-1005213Y348529D01*
G01D02*
X-1004950Y348569D01*
G01D02*
X-1004688Y348669D01*
G01D02*
X-1004538Y348789D01*
G01D02*
X-1004500Y348929D01*
G01D02*
X-1004575Y349089D01*
G01D02*
X-1004763Y349209D01*
G01D02*
X-1005100Y349329D01*
G01X-1001017Y355669D02*
Y340839D01*
G01X-994713Y347179D02*
X-996963D01*
G01D02*
Y347679D01*
G01D02*
X-996850Y347839D01*
G01D02*
X-996700Y347939D01*
G01D02*
X-996400Y347979D01*
G01D02*
X-996100Y347939D01*
G01D02*
X-995913Y347819D01*
G01D02*
X-995800Y347679D01*
G01D02*
Y347179D01*
G01Y347679D02*
X-994713Y347979D01*
G01Y348929D02*
X-994750Y349069D01*
G01D02*
X-994863Y349229D01*
G01D02*
X-995050Y349329D01*
G01D02*
X-995313Y349369D01*
G01D02*
X-995575Y349329D01*
G01D02*
X-995800Y349209D01*
G01D02*
X-995913Y349029D01*
G01D02*
Y348829D01*
G01D02*
X-995988Y348709D01*
G01D02*
X-996175Y348609D01*
G01D02*
X-996438Y348569D01*
G01D02*
X-996700Y348629D01*
G01D02*
X-996888Y348769D01*
G01D02*
X-996963Y348929D01*
G01D02*
X-996888Y349089D01*
G01D02*
X-996700Y349229D01*
G01D02*
X-996438Y349289D01*
G01D02*
X-996175Y349249D01*
G01D02*
X-995988Y349149D01*
G01D02*
X-995913Y349029D01*
G01D02*
Y348829D01*
G01D02*
X-995800Y348649D01*
G01D02*
X-995575Y348529D01*
G01D02*
X-995313Y348489D01*
G01D02*
X-995050Y348529D01*
G01D02*
X-994863Y348629D01*
G01D02*
X-994750Y348789D01*
G01D02*
X-994713Y348929D01*
G01X-992017Y340839D02*
X-999770D01*
G01D02*
Y355669D01*
G01X-1008770D02*
X-1001017D01*
G01X-999770D02*
X-992017D01*
G01X-991886Y225606D02*
Y217853D01*
G01Y233856D02*
Y226103D01*
G01Y242106D02*
Y234353D01*
G01Y250356D02*
Y242603D01*
G01Y258606D02*
Y250853D01*
G01Y266856D02*
Y259103D01*
G01Y275106D02*
Y267353D01*
G01Y283356D02*
Y275603D01*
G01Y291606D02*
Y283853D01*
G01Y299856D02*
Y292103D01*
G01X-992017Y355669D02*
Y340839D01*
G01X-974823Y9331D02*
Y182362D01*
G01X-967736Y64429D02*
Y411201D01*
G01X-851102Y64429D02*
X-967736D01*
G01Y411201D02*
X-851102D01*
G01X-960059Y48957D02*
G03X-957106Y46004I2953J0D01*
G01X-960059Y58051D02*
Y48957D01*
G01X-957106Y46004D02*
X-855827D01*
G01X-960059Y58051D02*
G03X-963012Y61004I-2953J0D01*
G01X-963159Y144862D02*
Y76949D01*
G01D02*
X-855679D01*
G01Y144862D02*
X-963159D01*
G01X-914919Y109905D02*
X-914482Y109155D01*
G01D02*
X-913957Y108655D01*
G01D02*
X-913344Y108405D01*
G01D02*
X-912644Y108655D01*
G01D02*
X-912119Y109155D01*
G01D02*
X-911594Y109905D01*
G01D02*
X-911419Y110905D01*
G01D02*
Y115905D01*
G01X-905669Y108405D02*
X-905057Y108530D01*
G01D02*
X-904357Y108905D01*
G01D02*
X-903919Y109530D01*
G01D02*
X-903744Y110405D01*
G01D02*
X-903919Y111280D01*
G01D02*
X-904444Y112030D01*
G01D02*
X-905232Y112405D01*
G01D02*
X-906107D01*
G01D02*
X-906632Y112655D01*
G01D02*
X-907069Y113280D01*
G01D02*
X-907244Y114155D01*
G01D02*
X-906982Y115030D01*
G01D02*
X-906369Y115655D01*
G01D02*
X-905669Y115905D01*
G01D02*
X-904969Y115655D01*
G01D02*
X-904357Y115030D01*
G01D02*
X-904094Y114155D01*
G01D02*
X-904269Y113280D01*
G01D02*
X-904707Y112655D01*
G01D02*
X-905232Y112405D01*
G01D02*
X-906107D01*
G01D02*
X-906894Y112030D01*
G01D02*
X-907419Y111280D01*
G01D02*
X-907594Y110405D01*
G01D02*
X-907419Y109530D01*
G01D02*
X-906982Y108905D01*
G01D02*
X-906282Y108530D01*
G01D02*
X-905669Y108405D01*
G01X-914919Y160555D02*
X-914482Y159805D01*
G01D02*
X-913957Y159305D01*
G01D02*
X-913344Y159055D01*
G01D02*
X-912644Y159305D01*
G01D02*
X-912119Y159805D01*
G01D02*
X-911594Y160555D01*
G01D02*
X-911419Y161555D01*
G01D02*
Y166555D01*
G01X-907157Y159930D02*
X-906544Y159305D01*
G01D02*
X-905844Y159055D01*
G01D02*
X-905144Y159305D01*
G01D02*
X-904532Y160055D01*
G01D02*
X-904094Y161180D01*
G01D02*
X-903919Y162305D01*
G01D02*
Y163680D01*
G01D02*
X-904094Y164805D01*
G01D02*
X-904532Y165805D01*
G01X-906894D02*
X-907244Y165055D01*
G01D02*
X-907419Y164055D01*
G01D02*
X-907244Y163180D01*
G01D02*
X-906807Y162305D01*
G01D02*
X-906282Y161805D01*
G01D02*
X-905669Y161680D01*
G01D02*
X-904969Y161930D01*
G01D02*
X-904444Y162555D01*
G01D02*
X-903919Y163680D01*
G01X-904532Y165805D02*
X-905057Y166305D01*
G01D02*
X-905669Y166555D01*
G01D02*
X-906369Y166305D01*
G01D02*
X-906894Y165805D01*
G01X-866156Y99895D02*
X-870006Y94395D01*
G01Y99895D02*
X-866156Y94395D01*
G01X-865456Y97146D02*
X-870706D01*
G01X-855827Y46004D02*
G03X-852874Y48957I0J2953D01*
G01X-855679Y76949D02*
Y144862D01*
G01X-868081Y93395D02*
Y100895D01*
G01X-842923Y2539D02*
X-772648D01*
G01X-842923Y163760D02*
Y2539D01*
G01X-852874Y48957D02*
Y58051D01*
G01X-849921Y61004D02*
X342106D01*
G01X-849921D02*
G03X-852874Y58051I0J-2953D01*
G01X-851102Y411201D02*
Y64429D01*
G01X-772648Y163760D02*
X-842923D01*
G01X-800226Y223572D02*
G03X-820305I-10039J14597D01*
G01X-826716Y267653D02*
Y275406D01*
G01X-811886Y267653D02*
X-826716D01*
G01Y275406D02*
X-811886D01*
G01X-826716Y276653D02*
Y284406D01*
G01X-811886Y276653D02*
X-826716D01*
G01Y284406D02*
X-811886D01*
G01X-826416Y285053D02*
Y292806D01*
G01X-811586Y285053D02*
X-826416D01*
G01Y293303D02*
Y301056D01*
G01X-811586Y293303D02*
X-826416D01*
G01Y301056D02*
X-811586D01*
G01X-826609Y302228D02*
Y309980D01*
G01X-811779Y302228D02*
X-826609D01*
G01X-826416Y292806D02*
X-811586D01*
G01X-826609Y317780D02*
X-811779D01*
G01X-826609Y310028D02*
Y317780D01*
G01X-811779Y310028D02*
X-826609D01*
G01X-826416Y318353D02*
Y326106D01*
G01X-811586Y318353D02*
X-826416D01*
G01X-826609Y309980D02*
X-811779D01*
G01X-826416Y326106D02*
X-811586D01*
G01X-826491Y326711D02*
Y334463D01*
G01X-811661Y326711D02*
X-826491D01*
G01Y334463D02*
X-811661D01*
G01X-826416Y335453D02*
Y343206D01*
G01X-811586Y335453D02*
X-826416D01*
G01Y343703D02*
Y351456D01*
G01X-811586Y343703D02*
X-826416D01*
G01Y351456D02*
X-811586D01*
G01X-826416Y352403D02*
Y360156D01*
G01X-811586Y352403D02*
X-826416D01*
G01Y343206D02*
X-811586D01*
G01X-826416Y360156D02*
X-811586D01*
G01X-818409Y132870D02*
X-817971Y132120D01*
G01D02*
X-817446Y131620D01*
G01D02*
X-816834Y131370D01*
G01D02*
X-816134Y131620D01*
G01D02*
X-815609Y132120D01*
G01D02*
X-815084Y132870D01*
G01D02*
X-814909Y133870D01*
G01X-809334Y131370D02*
X-809159Y132995D01*
G01D02*
X-808896Y134370D01*
G01X-814909Y133870D02*
Y138870D01*
G01X-808896Y134370D02*
X-808546Y135620D01*
G01D02*
X-808109Y136995D01*
G01D02*
X-807409Y138870D01*
G01D02*
X-810909D01*
G01X-820305Y202736D02*
G03X-800226I10039J0D01*
G01X-820305D02*
Y223572D01*
G01X-821051Y270780D02*
Y273030D01*
G01D02*
X-820551D01*
G01D02*
X-820391Y272917D01*
G01D02*
X-820291Y272767D01*
G01D02*
X-820251Y272467D01*
G01D02*
X-820291Y272167D01*
G01D02*
X-820411Y271980D01*
G01D02*
X-820551Y271867D01*
G01D02*
X-821051D01*
G01X-820551D02*
X-820251Y270780D01*
G01X-819301D02*
X-819161Y270817D01*
G01D02*
X-819001Y270930D01*
G01D02*
X-818901Y271117D01*
G01D02*
X-818861Y271380D01*
G01D02*
X-818901Y271642D01*
G01D02*
X-819021Y271867D01*
G01D02*
X-819201Y271980D01*
G01D02*
X-819401D01*
G01D02*
X-819521Y272055D01*
G01D02*
X-819621Y272242D01*
G01D02*
X-819661Y272504D01*
G01D02*
X-819601Y272767D01*
G01D02*
X-819461Y272955D01*
G01D02*
X-819301Y273030D01*
G01D02*
X-819141Y272955D01*
G01D02*
X-819001Y272767D01*
G01D02*
X-818941Y272504D01*
G01D02*
X-818981Y272242D01*
G01D02*
X-819081Y272055D01*
G01D02*
X-819201Y271980D01*
G01D02*
X-819401D01*
G01D02*
X-819581Y271867D01*
G01D02*
X-819701Y271642D01*
G01D02*
X-819741Y271380D01*
G01D02*
X-819701Y271117D01*
G01D02*
X-819601Y270930D01*
G01D02*
X-819441Y270817D01*
G01D02*
X-819301Y270780D01*
G01X-817951Y273030D02*
X-818111Y272955D01*
G01D02*
X-818231Y272767D01*
G01D02*
X-818311Y272542D01*
G01D02*
X-818371Y272242D01*
G01D02*
X-818391Y271904D01*
G01D02*
X-818371Y271567D01*
G01D02*
X-818311Y271267D01*
G01D02*
X-818231Y271042D01*
G01D02*
X-818111Y270855D01*
G01D02*
X-817951Y270780D01*
G01D02*
X-817791Y270855D01*
G01D02*
X-817671Y271042D01*
G01D02*
X-817591Y271267D01*
G01D02*
X-817531Y271567D01*
G01D02*
X-817511Y271904D01*
G01D02*
X-817531Y272242D01*
G01D02*
X-817591Y272542D01*
G01D02*
X-817671Y272767D01*
G01D02*
X-817791Y272955D01*
G01D02*
X-817951Y273030D01*
G01X-811886Y275406D02*
Y267653D01*
G01X-821051Y279348D02*
Y281598D01*
G01D02*
X-820551D01*
G01D02*
X-820391Y281486D01*
G01D02*
X-820291Y281336D01*
G01D02*
X-820251Y281036D01*
G01D02*
X-820291Y280736D01*
G01D02*
X-820411Y280548D01*
G01D02*
X-820551Y280436D01*
G01D02*
X-821051D01*
G01X-820551D02*
X-820251Y279348D01*
G01X-819301D02*
Y281598D01*
G01D02*
X-819541Y281148D01*
G01Y279348D02*
X-819061D01*
G01X-818331Y281223D02*
X-818211Y281448D01*
G01D02*
X-818071Y281561D01*
G01D02*
X-817911Y281598D01*
G01D02*
X-817711Y281523D01*
G01D02*
X-817571Y281336D01*
G01D02*
X-817531Y281111D01*
G01D02*
X-817551Y280886D01*
G01D02*
X-817631Y280698D01*
G01D02*
X-818031Y280323D01*
G01D02*
X-818211Y280061D01*
G01D02*
X-818331Y279686D01*
G01D02*
X-818371Y279348D01*
G01D02*
X-817531D01*
G01X-820376Y288030D02*
Y290280D01*
G01D02*
X-819876D01*
G01D02*
X-819716Y290167D01*
G01D02*
X-819616Y290017D01*
G01D02*
X-819576Y289717D01*
G01D02*
X-819616Y289417D01*
G01D02*
X-819736Y289230D01*
G01D02*
X-819876Y289117D01*
G01D02*
X-820376D01*
G01X-819876D02*
X-819576Y288030D01*
G01X-819066Y288367D02*
X-818946Y288180D01*
G01D02*
X-818806Y288067D01*
G01D02*
X-818626Y288030D01*
G01D02*
X-818446Y288105D01*
G01D02*
X-818306Y288254D01*
G01D02*
X-818206Y288517D01*
G01D02*
X-818186Y288817D01*
G01D02*
X-818226Y289117D01*
G01D02*
X-818326Y289305D01*
G01D02*
X-818466Y289454D01*
G01D02*
X-818606Y289492D01*
G01D02*
X-818746Y289454D01*
G01D02*
X-818926Y289305D01*
G01D02*
X-818866Y290280D01*
G01D02*
X-818326D01*
G01X-811886Y284406D02*
Y276653D01*
G01X-811586Y292806D02*
Y285053D01*
G01X-820376Y295530D02*
Y297780D01*
G01D02*
X-819876D01*
G01D02*
X-819716Y297667D01*
G01D02*
X-819616Y297517D01*
G01D02*
X-819576Y297217D01*
G01D02*
X-819616Y296917D01*
G01D02*
X-819736Y296730D01*
G01D02*
X-819876Y296617D01*
G01D02*
X-820376D01*
G01X-819876D02*
X-819576Y295530D01*
G01X-818386D02*
Y297780D01*
G01D02*
X-819126Y296167D01*
G01D02*
X-818126D01*
G01X-820944Y304923D02*
Y307173D01*
G01X-820444D02*
X-820284Y307060D01*
G01D02*
X-820184Y306910D01*
G01D02*
X-820144Y306610D01*
G01D02*
X-820184Y306310D01*
G01D02*
X-820304Y306123D01*
G01D02*
X-820444Y306010D01*
G01D02*
X-820944D01*
G01X-820444D02*
X-820144Y304923D01*
G01X-819574Y306798D02*
X-819454Y307023D01*
G01D02*
X-819314Y307135D01*
G01X-818954Y307098D02*
X-818814Y306910D01*
G01D02*
X-818774Y306685D01*
G01D02*
X-818794Y306460D01*
G01D02*
X-818874Y306273D01*
G01D02*
X-819274Y305898D01*
G01D02*
X-819454Y305635D01*
G01D02*
X-819574Y305260D01*
G01D02*
X-819614Y304923D01*
G01D02*
X-818774D01*
G01X-817604D02*
Y307173D01*
G01D02*
X-818344Y305560D01*
G01D02*
X-817344D01*
G01X-811586Y301056D02*
Y293303D01*
G01X-811779Y309980D02*
Y302228D01*
G01X-820944Y307173D02*
X-820444D01*
G01X-819314Y307135D02*
X-819154Y307173D01*
G01D02*
X-818954Y307098D01*
G01X-820944Y313585D02*
Y315835D01*
G01D02*
X-820444D01*
G01D02*
X-820284Y315722D01*
G01D02*
X-820184Y315573D01*
G01D02*
X-820144Y315273D01*
G01D02*
X-820184Y314973D01*
G01D02*
X-820304Y314785D01*
G01D02*
X-820444Y314672D01*
G01D02*
X-820944D01*
G01X-820444D02*
X-820144Y313585D01*
G01X-819574Y315460D02*
X-819454Y315685D01*
G01D02*
X-819314Y315798D01*
G01D02*
X-819154Y315835D01*
G01D02*
X-818954Y315760D01*
G01D02*
X-818814Y315573D01*
G01D02*
X-818774Y315348D01*
G01D02*
X-818794Y315122D01*
G01D02*
X-818874Y314935D01*
G01D02*
X-819274Y314560D01*
G01D02*
X-819454Y314298D01*
G01D02*
X-819574Y313922D01*
G01D02*
X-819614Y313585D01*
G01D02*
X-818774D01*
G01X-818284Y313922D02*
X-818164Y313735D01*
G01D02*
X-818024Y313623D01*
G01D02*
X-817844Y313585D01*
G01D02*
X-817664Y313660D01*
G01D02*
X-817524Y313810D01*
G01D02*
X-817424Y314072D01*
G01D02*
X-817404Y314372D01*
G01D02*
X-817444Y314672D01*
G01D02*
X-817544Y314860D01*
G01D02*
X-817684Y315010D01*
G01D02*
X-817824Y315047D01*
G01D02*
X-817964Y315010D01*
G01D02*
X-818144Y314860D01*
G01D02*
X-818084Y315835D01*
G01D02*
X-817544D01*
G01X-820751Y321048D02*
Y323298D01*
G01X-819991Y323036D02*
X-819951Y322736D01*
G01D02*
X-819991Y322436D01*
G01D02*
X-820111Y322248D01*
G01D02*
X-820251Y322136D01*
G01D02*
X-820751D01*
G01X-820251D02*
X-819951Y321048D01*
G01X-819001D02*
Y323298D01*
G01X-819241Y321048D02*
X-818761D01*
G01X-817411D02*
Y323298D01*
G01D02*
X-818151Y321686D01*
G01D02*
X-817151D01*
G01X-811779Y317780D02*
Y310028D01*
G01X-811586Y326106D02*
Y318353D01*
G01X-820751Y323298D02*
X-820251D01*
G01D02*
X-820091Y323186D01*
G01D02*
X-819991Y323036D01*
G01X-819001Y323298D02*
X-819241Y322848D01*
G01X-821051Y329280D02*
Y331530D01*
G01D02*
X-820551D01*
G01D02*
X-820391Y331417D01*
G01D02*
X-820291Y331267D01*
G01D02*
X-820251Y330967D01*
G01D02*
X-820291Y330667D01*
G01D02*
X-820411Y330480D01*
G01D02*
X-820551Y330367D01*
G01D02*
X-821051D01*
G01X-820551D02*
X-820251Y329280D01*
G01X-819681Y331155D02*
X-819561Y331380D01*
G01D02*
X-819421Y331492D01*
G01D02*
X-819261Y331530D01*
G01D02*
X-819061Y331455D01*
G01D02*
X-818921Y331267D01*
G01D02*
X-818881Y331042D01*
G01D02*
X-818901Y330817D01*
G01D02*
X-818981Y330630D01*
G01D02*
X-819381Y330255D01*
G01D02*
X-819561Y329992D01*
G01D02*
X-819681Y329617D01*
G01D02*
X-819721Y329280D01*
G01D02*
X-818881D01*
G01X-817991D02*
X-817951Y329767D01*
G01D02*
X-817891Y330179D01*
G01D02*
X-817811Y330555D01*
G01D02*
X-817711Y330967D01*
G01D02*
X-817551Y331530D01*
G01D02*
X-818351D01*
G01X-820751Y338148D02*
Y340398D01*
G01X-820251Y339236D02*
X-819951Y338148D01*
G01X-819001D02*
Y340398D01*
G01X-819241Y338148D02*
X-818761D01*
G01X-817291Y338636D02*
X-817371Y338411D01*
G01D02*
X-817491Y338223D01*
G01D02*
X-817631Y338148D01*
G01D02*
X-817791Y338223D01*
G01D02*
X-817931Y338448D01*
G01D02*
X-818011Y338786D01*
G01X-811661Y334463D02*
Y326711D01*
G01X-811586Y343206D02*
Y335453D01*
G01X-820751Y346398D02*
Y348648D01*
G01D02*
X-820251D01*
G01D02*
X-820091Y348536D01*
G01D02*
X-819991Y348386D01*
G01D02*
X-819951Y348086D01*
G01D02*
X-819991Y347786D01*
G01D02*
X-820111Y347598D01*
G01D02*
X-820251Y347486D01*
G01D02*
X-820751D01*
G01X-820251D02*
X-819951Y346398D01*
G01X-819001D02*
Y348648D01*
G01D02*
X-819241Y348198D01*
G01Y346398D02*
X-818761D01*
G01X-818091Y346736D02*
X-817971Y346548D01*
G01D02*
X-817831Y346436D01*
G01D02*
X-817651Y346398D01*
G01D02*
X-817471Y346473D01*
G01D02*
X-817331Y346623D01*
G01D02*
X-817231Y346886D01*
G01D02*
X-817211Y347186D01*
G01D02*
X-817251Y347486D01*
G01D02*
X-817351Y347673D01*
G01D02*
X-817491Y347823D01*
G01D02*
X-817631Y347861D01*
G01D02*
X-817771Y347823D01*
G01D02*
X-817951Y347673D01*
G01D02*
X-817891Y348648D01*
G01D02*
X-817351D01*
G01X-820751Y340398D02*
X-820251D01*
G01D02*
X-820091Y340286D01*
G01D02*
X-819991Y340136D01*
G01D02*
X-819951Y339836D01*
G01D02*
X-819991Y339536D01*
G01D02*
X-820111Y339348D01*
G01D02*
X-820251Y339236D01*
G01D02*
X-820751D01*
G01X-819001Y340398D02*
X-819241Y339948D01*
G01X-818031Y339086D02*
X-817891Y339348D01*
G01D02*
X-817771Y339498D01*
G01D02*
X-817611Y339573D01*
G01D02*
X-817471Y339498D01*
G01D02*
X-817371Y339348D01*
G01D02*
X-817291Y339123D01*
G01D02*
X-817271Y338861D01*
G01D02*
X-817291Y338636D01*
G01X-818011Y338786D02*
X-818031Y339161D01*
G01D02*
X-817991Y339648D01*
G01D02*
X-817931Y339911D01*
G01D02*
X-817831Y340173D01*
G01D02*
X-817691Y340361D01*
G01D02*
X-817551Y340398D01*
G01D02*
X-817411Y340323D01*
G01D02*
X-817311Y340136D01*
G01X-811586Y351456D02*
Y343703D01*
G01Y360156D02*
Y352403D01*
G01X-820301Y354780D02*
Y357030D01*
G01D02*
X-819801D01*
G01D02*
X-819641Y356917D01*
G01D02*
X-819541Y356767D01*
G01D02*
X-819501Y356467D01*
G01D02*
X-819541Y356167D01*
G01D02*
X-819661Y355980D01*
G01D02*
X-819801Y355867D01*
G01D02*
X-820301D01*
G01X-819801D02*
X-819501Y354780D01*
G01X-818931Y356655D02*
X-818811Y356880D01*
G01D02*
X-818671Y356992D01*
G01D02*
X-818511Y357030D01*
G01D02*
X-818311Y356955D01*
G01D02*
X-818171Y356767D01*
G01D02*
X-818131Y356542D01*
G01D02*
X-818151Y356317D01*
G01D02*
X-818231Y356130D01*
G01D02*
X-818631Y355755D01*
G01D02*
X-818811Y355492D01*
G01D02*
X-818931Y355117D01*
G01D02*
X-818971Y354780D01*
G01D02*
X-818131D01*
G01X-817541Y355042D02*
X-817401Y354855D01*
G01D02*
X-817241Y354780D01*
G01D02*
X-817081Y354855D01*
G01D02*
X-816941Y355079D01*
G01D02*
X-816841Y355417D01*
G01D02*
X-816801Y355755D01*
G01D02*
Y356167D01*
G01D02*
X-816841Y356504D01*
G01D02*
X-816941Y356805D01*
G01D02*
X-817061Y356955D01*
G01D02*
X-817201Y357030D01*
G01D02*
X-817361Y356955D01*
G01D02*
X-817481Y356805D01*
G01D02*
X-817561Y356580D01*
G01D02*
X-817601Y356279D01*
G01D02*
X-817561Y356017D01*
G01D02*
X-817461Y355755D01*
G01D02*
X-817341Y355604D01*
G01D02*
X-817201Y355567D01*
G01D02*
X-817041Y355642D01*
G01D02*
X-816921Y355830D01*
G01D02*
X-816801Y356167D01*
G01X-800226Y223572D02*
Y202736D01*
G01X-798216Y270906D02*
X-783386D01*
G01X-798216Y263153D02*
Y270906D01*
G01X-783386Y263153D02*
X-798216D01*
G01Y271403D02*
Y279156D01*
G01X-783386Y271403D02*
X-798216D01*
G01X-792551Y266711D02*
Y268961D01*
G01D02*
X-792051D01*
G01D02*
X-791891Y268848D01*
G01D02*
X-791791Y268698D01*
G01D02*
X-791751Y268398D01*
G01D02*
X-791791Y268098D01*
G01D02*
X-791911Y267911D01*
G01D02*
X-792051Y267798D01*
G01D02*
X-792551D01*
G01X-792051D02*
X-791751Y266711D01*
G01X-791181Y268586D02*
X-791061Y268811D01*
G01D02*
X-790921Y268923D01*
G01D02*
X-790761Y268961D01*
G01D02*
X-790561Y268886D01*
G01D02*
X-790421Y268698D01*
G01D02*
X-790381Y268473D01*
G01D02*
X-790401Y268248D01*
G01D02*
X-790481Y268061D01*
G01D02*
X-790881Y267686D01*
G01D02*
X-791061Y267423D01*
G01D02*
X-791181Y267048D01*
G01D02*
X-791221Y266711D01*
G01D02*
X-790381D01*
G01X-792551Y274961D02*
Y277211D01*
G01X-792051Y276048D02*
X-791751Y274961D01*
G01X-791061Y275673D02*
X-791181Y275298D01*
G01D02*
X-791221Y274961D01*
G01D02*
X-790381D01*
G01X-798216Y279653D02*
Y287406D01*
G01X-783386Y279653D02*
X-798216D01*
G01Y279156D02*
X-783386D01*
G01X-798216Y287406D02*
X-783386D01*
G01X-798216Y287903D02*
Y295656D01*
G01X-783386Y287903D02*
X-798216D01*
G01X-791876Y282348D02*
Y284598D01*
G01D02*
X-791376D01*
G01D02*
X-791216Y284486D01*
G01D02*
X-791116Y284336D01*
G01D02*
X-791076Y284036D01*
G01D02*
X-791116Y283736D01*
G01D02*
X-791236Y283548D01*
G01D02*
X-791376Y283436D01*
G01D02*
X-791876D01*
G01X-791376D02*
X-791076Y282348D01*
G01X-790566Y282798D02*
X-790446Y282536D01*
G01D02*
X-790286Y282386D01*
G01D02*
X-790106Y282348D01*
G01D02*
X-789946Y282386D01*
G01X-789846Y283473D02*
X-789986Y283548D01*
G01D02*
X-790166D01*
G01X-789986D02*
X-789866Y283661D01*
G01Y284486D02*
X-790046Y284598D01*
G01D02*
X-790226Y284561D01*
G01D02*
X-790406Y284411D01*
G01X-792551Y277211D02*
X-792051D01*
G01D02*
X-791891Y277098D01*
G01D02*
X-791791Y276948D01*
G01D02*
X-791751Y276648D01*
G01D02*
X-791791Y276348D01*
G01D02*
X-791911Y276161D01*
G01D02*
X-792051Y276048D01*
G01D02*
X-792551D01*
G01X-791181Y276836D02*
X-791061Y277061D01*
G01D02*
X-790921Y277173D01*
G01D02*
X-790761Y277211D01*
G01D02*
X-790561Y277136D01*
G01D02*
X-790421Y276948D01*
G01D02*
X-790381Y276723D01*
G01D02*
X-790401Y276498D01*
G01D02*
X-790481Y276311D01*
G01D02*
X-790881Y275936D01*
G01D02*
X-791061Y275673D01*
G01X-794540Y304837D02*
X-794660Y304950D01*
G01D02*
X-794800Y305024D01*
G01D02*
X-794960D01*
G01D02*
X-795140Y304912D01*
G01D02*
X-795280Y304724D01*
G01D02*
X-795380Y304499D01*
G01D02*
X-795460Y304124D01*
G01D02*
X-795480Y303787D01*
G01D02*
X-795440Y303450D01*
G01D02*
X-795380Y303224D01*
G01D02*
X-795260Y302999D01*
G01D02*
X-795120Y302849D01*
G01D02*
X-794980Y302774D01*
G01D02*
X-794840D01*
G01D02*
X-794700Y302849D01*
G01D02*
X-794580Y302962D01*
G01D02*
X-794480Y303112D01*
G01X-793390Y302774D02*
Y305024D01*
G01D02*
X-794130Y303412D01*
G01D02*
X-793130D01*
G01X-792280Y305024D02*
X-792440Y304950D01*
G01D02*
X-792560Y304762D01*
G01D02*
X-792640Y304537D01*
G01D02*
X-792700Y304237D01*
G01D02*
X-792720Y303899D01*
G01D02*
X-792700Y303562D01*
G01D02*
X-792640Y303262D01*
G01D02*
X-792560Y303037D01*
G01D02*
X-792440Y302849D01*
G01D02*
X-792280Y302774D01*
G01D02*
X-792120Y302849D01*
G01D02*
X-792000Y303037D01*
G01D02*
X-791920Y303262D01*
G01D02*
X-791860Y303562D01*
G01D02*
X-791840Y303899D01*
G01D02*
X-791860Y304237D01*
G01D02*
X-791920Y304537D01*
G01D02*
X-792000Y304762D01*
G01D02*
X-792120Y304950D01*
G01D02*
X-792280Y305024D01*
G01X-801695Y298778D02*
Y309530D01*
G01X-783592Y298778D02*
X-801695D01*
G01X-798216Y295656D02*
X-783386D01*
G01X-791876Y291461D02*
Y293711D01*
G01D02*
X-791376D01*
G01D02*
X-791216Y293598D01*
G01D02*
X-791116Y293448D01*
G01D02*
X-791076Y293148D01*
G01D02*
X-791116Y292848D01*
G01D02*
X-791236Y292661D01*
G01D02*
X-791376Y292548D01*
G01D02*
X-791876D01*
G01X-791376D02*
X-791076Y291461D01*
G01X-790506Y293336D02*
X-790386Y293561D01*
G01D02*
X-790246Y293673D01*
G01D02*
X-790086Y293711D01*
G01D02*
X-789886Y293636D01*
G01X-789806Y292811D02*
X-790206Y292436D01*
G01D02*
X-790386Y292173D01*
G01D02*
X-790506Y291798D01*
G01D02*
X-790546Y291461D01*
G01D02*
X-789706D01*
G01X-801695Y309530D02*
X-783592D01*
G01X-798109Y319778D02*
Y327530D01*
G01X-783279Y319778D02*
X-798109D01*
G01Y311978D02*
Y319730D01*
G01X-783279Y311978D02*
X-798109D01*
G01Y319730D02*
X-783279D01*
G01X-792444Y314673D02*
Y316923D01*
G01D02*
X-791944D01*
G01D02*
X-791784Y316810D01*
G01D02*
X-791684Y316660D01*
G01D02*
X-791644Y316360D01*
G01D02*
X-791684Y316060D01*
G01D02*
X-791804Y315873D01*
G01D02*
X-791944Y315760D01*
G01D02*
X-792444D01*
G01X-791944D02*
X-791644Y314673D01*
G01X-791074Y316548D02*
X-790954Y316773D01*
G01D02*
X-790814Y316885D01*
G01D02*
X-790654Y316923D01*
G01D02*
X-790454Y316848D01*
G01D02*
X-790314Y316660D01*
G01D02*
X-790274Y316435D01*
G01D02*
X-790294Y316210D01*
G01D02*
X-790374Y316023D01*
G01D02*
X-790774Y315648D01*
G01D02*
X-790954Y315385D01*
G01D02*
X-791074Y315010D01*
G01D02*
X-791114Y314673D01*
G01D02*
X-790274D01*
G01X-798109Y327530D02*
X-783279D01*
G01X-798109Y328028D02*
Y335780D01*
G01X-783279Y328028D02*
X-798109D01*
G01Y336278D02*
Y344030D01*
G01X-783279Y336278D02*
X-798109D01*
G01Y335780D02*
X-783279D01*
G01X-792444Y323335D02*
Y325585D01*
G01D02*
X-791944D01*
G01D02*
X-791784Y325472D01*
G01D02*
X-791684Y325323D01*
G01D02*
X-791644Y325023D01*
G01D02*
X-791684Y324723D01*
G01D02*
X-791804Y324535D01*
G01D02*
X-791944Y324422D01*
G01D02*
X-792444D01*
G01X-791944D02*
X-791644Y323335D01*
G01X-791074Y325210D02*
X-790954Y325435D01*
G01D02*
X-790814Y325548D01*
G01D02*
X-790654Y325585D01*
G01D02*
X-790454Y325510D01*
G01D02*
X-790314Y325323D01*
G01D02*
X-790274Y325098D01*
G01D02*
X-790294Y324872D01*
G01D02*
X-790374Y324685D01*
G01D02*
X-790774Y324310D01*
G01D02*
X-790954Y324048D01*
G01D02*
X-791074Y323672D01*
G01D02*
X-791114Y323335D01*
G01D02*
X-790274D01*
G01X-792444Y330723D02*
Y332973D01*
G01D02*
X-791944D01*
G01D02*
X-791784Y332860D01*
G01D02*
X-791684Y332710D01*
G01D02*
X-791644Y332410D01*
G01D02*
X-791684Y332110D01*
G01D02*
X-791804Y331923D01*
G01D02*
X-791944Y331810D01*
G01D02*
X-792444D01*
G01X-791944D02*
X-791644Y330723D01*
G01X-791074Y332598D02*
X-790954Y332823D01*
G01D02*
X-790814Y332935D01*
G01D02*
X-790654Y332973D01*
G01D02*
X-790454Y332898D01*
G01D02*
X-790314Y332710D01*
G01D02*
X-790274Y332485D01*
G01D02*
X-790294Y332260D01*
G01D02*
X-790374Y332073D01*
G01D02*
X-790774Y331698D01*
G01D02*
X-790954Y331435D01*
G01D02*
X-791074Y331060D01*
G01D02*
X-791114Y330723D01*
G01D02*
X-790274D01*
G01X-798109Y352028D02*
Y359780D01*
G01X-783279Y352028D02*
X-798109D01*
G01Y344030D02*
X-783279D01*
G01X-798109Y344228D02*
Y351980D01*
G01X-783279Y344228D02*
X-798109D01*
G01Y351980D02*
X-783279D01*
G01X-792444Y339835D02*
Y342085D01*
G01D02*
X-791944D01*
G01D02*
X-791784Y341972D01*
G01D02*
X-791684Y341823D01*
G01D02*
X-791644Y341523D01*
G01D02*
X-791684Y341223D01*
G01D02*
X-791804Y341035D01*
G01D02*
X-791944Y340922D01*
G01D02*
X-792444D01*
G01X-791944D02*
X-791644Y339835D01*
G01X-791074Y341710D02*
X-790954Y341935D01*
G01D02*
X-790814Y342048D01*
G01D02*
X-790654Y342085D01*
G01D02*
X-790454Y342010D01*
G01D02*
X-790314Y341823D01*
G01D02*
X-790274Y341598D01*
G01D02*
X-790294Y341372D01*
G01D02*
X-790374Y341185D01*
G01D02*
X-790774Y340810D01*
G01D02*
X-790954Y340548D01*
G01D02*
X-791074Y340172D01*
G01D02*
X-791114Y339835D01*
G01D02*
X-790274D01*
G01X-792444Y346923D02*
Y349173D01*
G01D02*
X-791944D01*
G01D02*
X-791784Y349060D01*
G01D02*
X-791684Y348910D01*
G01D02*
X-791644Y348610D01*
G01D02*
X-791684Y348310D01*
G01D02*
X-791804Y348123D01*
G01D02*
X-791944Y348010D01*
G01D02*
X-792444D01*
G01X-791944D02*
X-791644Y346923D01*
G01X-790694D02*
Y349173D01*
G01D02*
X-790934Y348723D01*
G01Y346923D02*
X-790454D01*
G01X-798109Y359780D02*
X-783279D01*
G01X-792444Y355585D02*
Y357835D01*
G01D02*
X-791944D01*
G01D02*
X-791784Y357722D01*
G01D02*
X-791684Y357573D01*
G01D02*
X-791644Y357273D01*
G01D02*
X-791684Y356973D01*
G01D02*
X-791804Y356785D01*
G01D02*
X-791944Y356672D01*
G01D02*
X-792444D01*
G01X-791944D02*
X-791644Y355585D01*
G01X-790694D02*
Y357835D01*
G01D02*
X-790934Y357385D01*
G01Y355585D02*
X-790454D01*
G01X-776333Y76136D02*
X-780183Y70636D01*
G01X-778258Y69636D02*
Y77136D01*
G01X-780183Y76136D02*
X-776333Y70636D01*
G01X-775633Y73386D02*
X-780883D01*
G01X-789831Y267648D02*
X-789691Y267911D01*
G01D02*
X-789571Y268061D01*
G01D02*
X-789411Y268136D01*
G01D02*
X-789271Y268061D01*
G01D02*
X-789171Y267911D01*
G01D02*
X-789091Y267686D01*
G01D02*
X-789071Y267423D01*
G01D02*
X-789091Y267198D01*
G01D02*
X-789171Y266973D01*
G01D02*
X-789291Y266786D01*
G01D02*
X-789431Y266711D01*
G01D02*
X-789591Y266786D01*
G01D02*
X-789731Y267011D01*
G01D02*
X-789811Y267348D01*
G01D02*
X-789831Y267723D01*
G01D02*
X-789791Y268211D01*
G01D02*
X-789731Y268473D01*
G01D02*
X-789631Y268736D01*
G01D02*
X-789491Y268923D01*
G01D02*
X-789351Y268961D01*
G01D02*
X-789211Y268886D01*
G01D02*
X-789111Y268698D01*
G01X-783386Y270906D02*
Y263153D01*
G01X-789451Y274961D02*
X-789311Y274998D01*
G01D02*
X-789151Y275111D01*
G01D02*
X-789051Y275298D01*
G01D02*
X-789011Y275561D01*
G01D02*
X-789051Y275823D01*
G01X-789851D02*
X-789891Y275561D01*
G01D02*
X-789851Y275298D01*
G01D02*
X-789751Y275111D01*
G01D02*
X-789591Y274998D01*
G01D02*
X-789451Y274961D01*
G01X-783386Y279156D02*
Y271403D01*
G01X-789946Y282386D02*
X-789786Y282573D01*
G01D02*
X-789686Y282798D01*
G01D02*
X-789666Y283023D01*
G01D02*
X-789706Y283286D01*
G01D02*
X-789846Y283473D01*
G01X-789866Y283661D02*
X-789766Y283848D01*
G01D02*
X-789726Y284073D01*
G01D02*
X-789766Y284298D01*
G01D02*
X-789866Y284486D01*
G01X-783386Y287406D02*
Y279653D01*
G01X-789051Y275823D02*
X-789171Y276048D01*
G01D02*
X-789351Y276161D01*
G01D02*
X-789551D01*
G01D02*
X-789671Y276236D01*
G01D02*
X-789771Y276423D01*
G01D02*
X-789811Y276686D01*
G01D02*
X-789751Y276948D01*
G01D02*
X-789611Y277136D01*
G01D02*
X-789451Y277211D01*
G01D02*
X-789291Y277136D01*
G01D02*
X-789151Y276948D01*
G01D02*
X-789091Y276686D01*
G01D02*
X-789131Y276423D01*
G01D02*
X-789231Y276236D01*
G01D02*
X-789351Y276161D01*
G01D02*
X-789551D01*
G01D02*
X-789731Y276048D01*
G01D02*
X-789851Y275823D01*
G01X-783386Y295656D02*
Y287903D01*
G01X-783592Y309530D02*
Y298778D01*
G01X-789886Y293636D02*
X-789746Y293448D01*
G01D02*
X-789706Y293223D01*
G01D02*
X-789726Y292998D01*
G01D02*
X-789806Y292811D01*
G01X-783279Y327530D02*
Y319778D01*
G01X-789724Y316548D02*
X-789604Y316773D01*
G01D02*
X-789464Y316885D01*
G01D02*
X-789304Y316923D01*
G01D02*
X-789104Y316848D01*
G01D02*
X-788964Y316660D01*
G01D02*
X-788924Y316435D01*
G01D02*
X-788944Y316210D01*
G01D02*
X-789024Y316023D01*
G01D02*
X-789424Y315648D01*
G01D02*
X-789604Y315385D01*
G01D02*
X-789724Y315010D01*
G01D02*
X-789764Y314673D01*
G01D02*
X-788924D01*
G01X-783279Y319730D02*
Y311978D01*
G01X-789784Y323785D02*
X-789664Y323522D01*
G01D02*
X-789504Y323373D01*
G01D02*
X-789324Y323335D01*
G01D02*
X-789164Y323373D01*
G01D02*
X-789004Y323560D01*
G01D02*
X-788904Y323785D01*
G01D02*
X-788884Y324010D01*
G01D02*
X-788924Y324272D01*
G01D02*
X-789064Y324460D01*
G01D02*
X-789204Y324535D01*
G01D02*
X-789384D01*
G01X-789204D02*
X-789084Y324648D01*
G01D02*
X-788984Y324835D01*
G01D02*
X-788944Y325060D01*
G01D02*
X-788984Y325285D01*
G01D02*
X-789084Y325472D01*
G01D02*
X-789264Y325585D01*
G01D02*
X-789444Y325548D01*
G01D02*
X-789624Y325398D01*
G01X-783279Y335780D02*
Y328028D01*
G01Y344030D02*
Y336278D01*
G01X-789344Y332973D02*
X-789504Y332898D01*
G01D02*
X-789624Y332710D01*
G01D02*
X-789704Y332485D01*
G01D02*
X-789764Y332185D01*
G01D02*
X-789784Y331848D01*
G01D02*
X-789764Y331510D01*
G01D02*
X-789704Y331210D01*
G01D02*
X-789624Y330985D01*
G01D02*
X-789504Y330798D01*
G01D02*
X-789344Y330723D01*
G01D02*
X-789184Y330798D01*
G01D02*
X-789064Y330985D01*
G01D02*
X-788984Y331210D01*
G01D02*
X-788924Y331510D01*
G01D02*
X-788904Y331848D01*
G01D02*
X-788924Y332185D01*
G01D02*
X-788984Y332485D01*
G01D02*
X-789064Y332710D01*
G01D02*
X-789184Y332898D01*
G01D02*
X-789344Y332973D01*
G01X-783279Y359780D02*
Y352028D01*
G01X-789344Y339835D02*
Y342085D01*
G01D02*
X-789584Y341635D01*
G01Y339835D02*
X-789104D01*
G01X-789344Y346923D02*
X-789204Y346960D01*
G01D02*
X-789044Y347073D01*
G01D02*
X-788944Y347260D01*
G01D02*
X-788904Y347523D01*
G01D02*
X-788944Y347785D01*
G01D02*
X-789064Y348010D01*
G01D02*
X-789244Y348123D01*
G01D02*
X-789444D01*
G01D02*
X-789564Y348198D01*
G01D02*
X-789664Y348385D01*
G01D02*
X-789704Y348648D01*
G01D02*
X-789644Y348910D01*
G01D02*
X-789504Y349098D01*
G01D02*
X-789344Y349173D01*
G01D02*
X-789184Y349098D01*
G01D02*
X-789044Y348910D01*
G01D02*
X-788984Y348648D01*
G01D02*
X-789024Y348385D01*
G01D02*
X-789124Y348198D01*
G01D02*
X-789244Y348123D01*
G01D02*
X-789444D01*
G01D02*
X-789624Y348010D01*
G01D02*
X-789744Y347785D01*
G01D02*
X-789784Y347523D01*
G01D02*
X-789744Y347260D01*
G01D02*
X-789644Y347073D01*
G01D02*
X-789484Y346960D01*
G01D02*
X-789344Y346923D01*
G01X-783279Y351980D02*
Y344228D01*
G01X-789684Y355847D02*
X-789544Y355660D01*
G01D02*
X-789384Y355585D01*
G01D02*
X-789224Y355660D01*
G01D02*
X-789084Y355885D01*
G01D02*
X-788984Y356223D01*
G01D02*
X-788944Y356560D01*
G01D02*
Y356973D01*
G01D02*
X-788984Y357310D01*
G01D02*
X-789084Y357610D01*
G01D02*
X-789204Y357760D01*
G01D02*
X-789344Y357835D01*
G01D02*
X-789504Y357760D01*
G01D02*
X-789624Y357610D01*
G01D02*
X-789704Y357385D01*
G01D02*
X-789744Y357085D01*
G01D02*
X-789704Y356823D01*
G01D02*
X-789604Y356560D01*
G01D02*
X-789484Y356410D01*
G01D02*
X-789344Y356372D01*
G01D02*
X-789184Y356447D01*
G01D02*
X-789064Y356635D01*
G01D02*
X-788944Y356973D01*
G01X-772648Y2539D02*
Y163760D01*
G01X-759419Y114626D02*
X-663750D01*
G01X-759419Y402343D02*
Y114626D01*
G01X-663750Y402343D02*
X-759419D01*
G01X-744065Y129213D02*
X-685010D01*
G01X-744065Y174685D02*
Y129213D01*
G01X-679104Y174685D02*
X-744065D01*
G01X-727801Y74280D02*
Y68280D01*
G01D02*
X-715801D01*
G01X-737781Y69780D02*
Y72030D01*
G01X-736471Y70079D02*
X-736311Y69892D01*
G01D02*
X-736131Y69780D01*
G01D02*
X-735971D01*
G01D02*
X-735811Y69892D01*
G01D02*
X-735691Y70079D01*
G01D02*
X-735631Y70342D01*
G01D02*
X-735671Y70604D01*
G01D02*
X-735771Y70830D01*
G01D02*
X-735951Y70980D01*
G01X-734701Y69780D02*
Y72030D01*
G01X-734941Y69780D02*
X-734461D01*
G01X-741969Y74406D02*
Y68453D01*
G01X-730133D02*
Y74406D01*
G01X-741969Y68453D02*
X-730133D01*
G01X-737781Y72030D02*
X-737021D01*
G01X-737301Y70942D02*
X-737781D01*
G01X-735951Y70980D02*
X-736191Y71055D01*
G01D02*
X-736331Y71204D01*
G01D02*
X-736391Y71467D01*
G01D02*
X-736351Y71730D01*
G01D02*
X-736251Y71917D01*
G01D02*
X-736111Y72030D01*
G01D02*
X-735971D01*
G01D02*
X-735831Y71955D01*
G01D02*
X-735711Y71767D01*
G01X-734701Y72030D02*
X-734941Y71580D01*
G01X-728195Y82328D02*
X-716392D01*
G01X-728195Y88280D02*
Y82328D01*
G01Y75578D02*
X-716392D01*
G01X-728195Y81530D02*
Y75578D01*
G01X-716392Y81530D02*
X-728195D01*
G01X-715801Y74280D02*
X-727801D01*
G01X-730133Y74406D02*
X-741969D01*
G01X-716392Y88280D02*
X-728195D01*
G01X-723185Y70342D02*
Y72592D01*
G01X-721915D02*
Y70342D01*
G01D02*
X-721255D01*
G01D02*
X-721115Y70492D01*
G01D02*
X-721035Y70717D01*
G01D02*
X-720995Y70979D01*
G01X-720105Y70342D02*
Y72592D01*
G01X-720345Y70342D02*
X-719865D01*
G01X-715801Y68280D02*
Y74280D01*
G01X-707917Y68889D02*
X-715670D01*
G01D02*
Y83719D01*
G01X-723185Y72592D02*
X-722425D01*
G01X-722705Y71504D02*
X-723185D01*
G01X-721295Y71542D02*
X-721215Y71654D01*
G01D02*
X-721155Y71842D01*
G01D02*
X-721115Y72104D01*
G01D02*
X-721155Y72329D01*
G01D02*
X-721235Y72479D01*
G01D02*
X-721375Y72592D01*
G01D02*
X-721915D01*
G01X-720995Y70979D02*
X-721035Y71242D01*
G01D02*
X-721155Y71467D01*
G01D02*
X-721295Y71542D01*
G01D02*
X-721915D01*
G01X-720105Y72592D02*
X-720345Y72142D01*
G01X-723269Y86787D02*
X-723369Y86562D01*
G01D02*
X-723449Y86187D01*
G01D02*
X-723469Y85850D01*
G01D02*
X-723429Y85512D01*
G01D02*
X-723369Y85287D01*
G01D02*
X-723249Y85062D01*
G01D02*
X-723109Y84912D01*
G01D02*
X-722969Y84837D01*
G01D02*
X-722829D01*
G01D02*
X-722689Y84912D01*
G01D02*
X-722569Y85025D01*
G01D02*
X-722469Y85175D01*
G01X-721659Y84837D02*
X-721619Y85325D01*
G01D02*
X-721559Y85737D01*
G01D02*
X-721479Y86112D01*
G01D02*
X-721379Y86525D01*
G01D02*
X-721219Y87087D01*
G01X-722529Y80150D02*
X-722649Y80262D01*
G01D02*
X-722789Y80337D01*
G01D02*
X-722949D01*
G01D02*
X-723129Y80225D01*
G01D02*
X-723269Y80037D01*
G01D02*
X-723369Y79812D01*
G01D02*
X-723449Y79437D01*
G01D02*
X-723469Y79100D01*
G01D02*
X-723429Y78762D01*
G01D02*
X-723369Y78537D01*
G01D02*
X-723249Y78312D01*
G01D02*
X-723109Y78162D01*
G01D02*
X-722969Y78087D01*
G01D02*
X-722829D01*
G01D02*
X-722689Y78162D01*
G01D02*
X-722569Y78275D01*
G01D02*
X-722469Y78425D01*
G01X-721619Y78087D02*
X-721479Y78125D01*
G01D02*
X-721319Y78237D01*
G01D02*
X-721219Y78425D01*
G01D02*
X-721179Y78687D01*
G01D02*
X-721219Y78950D01*
G01D02*
X-721339Y79175D01*
G01D02*
X-721519Y79287D01*
G01D02*
X-721719D01*
G01D02*
X-721839Y79362D01*
G01D02*
X-721939Y79550D01*
G01D02*
X-721979Y79812D01*
G01D02*
X-721919Y80075D01*
G01D02*
X-721779Y80262D01*
G01D02*
X-721619Y80337D01*
G01D02*
X-721459Y80262D01*
G01D02*
X-721319Y80075D01*
G01D02*
X-721259Y79812D01*
G01D02*
X-721299Y79550D01*
G01D02*
X-721399Y79362D01*
G01D02*
X-721519Y79287D01*
G01D02*
X-721719D01*
G01D02*
X-721899Y79175D01*
G01D02*
X-722019Y78950D01*
G01D02*
X-722059Y78687D01*
G01D02*
X-722019Y78425D01*
G01D02*
X-721919Y78237D01*
G01D02*
X-721759Y78125D01*
G01D02*
X-721619Y78087D01*
G01X-716392Y82328D02*
Y88280D01*
G01Y75578D02*
Y81530D01*
G01X-710613Y74554D02*
X-712863D01*
G01D02*
Y75054D01*
G01D02*
X-712750Y75214D01*
G01D02*
X-712600Y75314D01*
G01D02*
X-712300Y75354D01*
G01D02*
X-712000Y75314D01*
G01D02*
X-711813Y75194D01*
G01D02*
X-711700Y75054D01*
G01D02*
Y74554D01*
G01Y75054D02*
X-710613Y75354D01*
G01Y76304D02*
X-712863D01*
G01D02*
X-712413Y76064D01*
G01X-711063Y78094D02*
X-711288Y78114D01*
G01D02*
X-711550Y78074D01*
G01D02*
X-711738Y77934D01*
G01D02*
X-711813Y77794D01*
G01D02*
Y77614D01*
G01Y77794D02*
X-711925Y77914D01*
G01D02*
X-712113Y78014D01*
G01D02*
X-712338Y78054D01*
G01D02*
X-712563Y78014D01*
G01D02*
X-712750Y77914D01*
G01D02*
X-712863Y77734D01*
G01D02*
X-712825Y77554D01*
G01D02*
X-712675Y77374D01*
G01X-715670Y83719D02*
X-707917D01*
G01X-722529Y86900D02*
X-722649Y87012D01*
G01D02*
X-722789Y87087D01*
G01D02*
X-722949D01*
G01D02*
X-723129Y86975D01*
G01D02*
X-723269Y86787D01*
G01X-721219Y87087D02*
X-722019D01*
G01X-709660Y121195D02*
X-713510Y115695D01*
G01X-711585Y114695D02*
Y122195D01*
G01X-713510Y121195D02*
X-709660Y115695D01*
G01X-708960Y118445D02*
X-714210D01*
G01X-717085Y151992D02*
X-716647Y151242D01*
G01D02*
X-716122Y150742D01*
G01D02*
X-715510Y150492D01*
G01D02*
X-714810Y150742D01*
G01D02*
X-714285Y151242D01*
G01D02*
X-713760Y151992D01*
G01D02*
X-713585Y152992D01*
G01D02*
Y157992D01*
G01X-717085Y229945D02*
X-716647Y229195D01*
G01D02*
X-716122Y228695D01*
G01D02*
X-715510Y228445D01*
G01D02*
X-714810Y228695D01*
G01D02*
X-714285Y229195D01*
G01D02*
X-713760Y229945D01*
G01D02*
X-713585Y230945D01*
G01D02*
Y235945D01*
G01X-707917Y83719D02*
Y68889D01*
G01X-707420D02*
Y83719D01*
G01X-699667Y68889D02*
X-707420D01*
G01X-699667Y83719D02*
Y68889D01*
G01X-699044Y74804D02*
Y68804D01*
G01D02*
X-687044D01*
G01X-710613Y76064D02*
Y76544D01*
G01X-711063Y77214D02*
X-710800Y77334D01*
G01D02*
X-710650Y77494D01*
G01D02*
X-710613Y77674D01*
G01D02*
X-710650Y77834D01*
G01D02*
X-710838Y77994D01*
G01D02*
X-711063Y78094D01*
G01X-703225Y74554D02*
X-705475D01*
G01D02*
Y75054D01*
G01D02*
X-705362Y75214D01*
G01D02*
X-705212Y75314D01*
G01D02*
X-704912Y75354D01*
G01D02*
X-704612Y75314D01*
G01D02*
X-704425Y75194D01*
G01D02*
X-704312Y75054D01*
G01D02*
Y74554D01*
G01Y75054D02*
X-703225Y75354D01*
G01Y76304D02*
X-705475D01*
G01D02*
X-705025Y76064D01*
G01X-703225D02*
Y76544D01*
G01Y77614D02*
X-703712Y77654D01*
G01D02*
X-704125Y77714D01*
G01D02*
X-704500Y77794D01*
G01D02*
X-704912Y77894D01*
G01D02*
X-705475Y78054D01*
G01D02*
Y77254D01*
G01X-707420Y83719D02*
X-699667D01*
G01X-698945Y81530D02*
Y75578D01*
G01X-687142Y81530D02*
X-698945D01*
G01Y75578D02*
X-687142D01*
G01X-698945Y88280D02*
Y82328D01*
G01D02*
X-687142D01*
G01X-687044Y74804D02*
X-699044D01*
G01X-687142Y88280D02*
X-698945D01*
G01X-709760Y151617D02*
X-709235Y150992D01*
G01D02*
X-708622Y150617D01*
G01D02*
X-707835Y150492D01*
G01D02*
X-707047Y150742D01*
G01D02*
X-706435Y151242D01*
G01D02*
X-705997Y152117D01*
G01D02*
X-705910Y153117D01*
G01D02*
X-706085Y154117D01*
G01D02*
X-706522Y154742D01*
G01D02*
X-707135Y155242D01*
G01D02*
X-707747Y155367D01*
G01D02*
X-708360Y155242D01*
G01D02*
X-709147Y154742D01*
G01D02*
X-708885Y157992D01*
G01D02*
X-706522D01*
G01X-709497Y231570D02*
X-708885Y232445D01*
G01D02*
X-708360Y232945D01*
G01D02*
X-707660Y233195D01*
G01D02*
X-707047Y232945D01*
G01D02*
X-706610Y232445D01*
G01D02*
X-706260Y231695D01*
G01D02*
X-706172Y230820D01*
G01D02*
X-706260Y230070D01*
G01D02*
X-706610Y229320D01*
G01D02*
X-707135Y228695D01*
G01D02*
X-707747Y228445D01*
G01D02*
X-708447Y228695D01*
G01D02*
X-709060Y229445D01*
G01D02*
X-709410Y230570D01*
G01D02*
X-709497Y231820D01*
G01D02*
X-709322Y233445D01*
G01D02*
X-709060Y234320D01*
G01D02*
X-708622Y235195D01*
G01D02*
X-708010Y235820D01*
G01D02*
X-707397Y235945D01*
G01D02*
X-706785Y235695D01*
G01D02*
X-706347Y235070D01*
G01X-687044Y68804D02*
Y74804D01*
G01X-683169Y74706D02*
Y68753D01*
G01D02*
X-671333D01*
G01X-694708Y70375D02*
Y72625D01*
G01X-693438D02*
Y70375D01*
G01D02*
X-692778D01*
G01D02*
X-692638Y70525D01*
G01D02*
X-692558Y70750D01*
G01D02*
X-692518Y71013D01*
G01X-691888Y71088D02*
X-692008Y70713D01*
G01D02*
X-692048Y70375D01*
G01D02*
X-691208D01*
G01X-693279Y79583D02*
X-693399Y79695D01*
G01D02*
X-693539Y79770D01*
G01D02*
X-693699D01*
G01D02*
X-693879Y79658D01*
G01D02*
X-694019Y79470D01*
G01D02*
X-694119Y79245D01*
G01D02*
X-694199Y78870D01*
G01D02*
X-694219Y78533D01*
G01D02*
X-694179Y78195D01*
G01D02*
X-694119Y77970D01*
G01D02*
X-693999Y77745D01*
G01D02*
X-693859Y77595D01*
G01D02*
X-693719Y77520D01*
G01D02*
X-693579D01*
G01D02*
X-693439Y77595D01*
G01D02*
X-693319Y77708D01*
G01D02*
X-693219Y77858D01*
G01X-692749Y78458D02*
X-692609Y78720D01*
G01D02*
X-692489Y78870D01*
G01D02*
X-692329Y78945D01*
G01D02*
X-692189Y78870D01*
G01D02*
X-692089Y78720D01*
G01D02*
X-692009Y78495D01*
G01D02*
X-691989Y78233D01*
G01D02*
X-692009Y78008D01*
G01D02*
X-692089Y77783D01*
G01D02*
X-692209Y77595D01*
G01D02*
X-692349Y77520D01*
G01D02*
X-692509Y77595D01*
G01D02*
X-692649Y77820D01*
G01D02*
X-692729Y78158D01*
G01D02*
X-692749Y78533D01*
G01D02*
X-692709Y79020D01*
G01D02*
X-692649Y79283D01*
G01D02*
X-692549Y79545D01*
G01D02*
X-692409Y79733D01*
G01D02*
X-692269Y79770D01*
G01D02*
X-692129Y79695D01*
G01D02*
X-692029Y79508D01*
G01X-687142Y75578D02*
Y81530D01*
G01X-693279Y86333D02*
X-693399Y86445D01*
G01D02*
X-693539Y86520D01*
G01D02*
X-693699D01*
G01D02*
X-693879Y86408D01*
G01D02*
X-694019Y86220D01*
G01D02*
X-694119Y85995D01*
G01D02*
X-694199Y85620D01*
G01D02*
X-694219Y85283D01*
G01D02*
X-694179Y84945D01*
G01D02*
X-694119Y84720D01*
G01D02*
X-693999Y84495D01*
G01D02*
X-693859Y84345D01*
G01D02*
X-693719Y84270D01*
G01D02*
X-693579D01*
G01D02*
X-693439Y84345D01*
G01D02*
X-693319Y84458D01*
G01D02*
X-693219Y84608D01*
G01X-692809D02*
X-692689Y84420D01*
G01D02*
X-692549Y84308D01*
G01D02*
X-692369Y84270D01*
G01D02*
X-692189Y84345D01*
G01D02*
X-692049Y84495D01*
G01D02*
X-691949Y84758D01*
G01D02*
X-691929Y85058D01*
G01D02*
X-691969Y85358D01*
G01D02*
X-692069Y85545D01*
G01D02*
X-692209Y85695D01*
G01D02*
X-692349Y85733D01*
G01D02*
X-692489Y85695D01*
G01D02*
X-692669Y85545D01*
G01D02*
X-692609Y86520D01*
G01D02*
X-692069D01*
G01X-687142Y82328D02*
Y88280D01*
G01X-694708Y72625D02*
X-693948D01*
G01X-694228Y71538D02*
X-694708D01*
G01X-692818Y71575D02*
X-692738Y71688D01*
G01D02*
X-692678Y71875D01*
G01D02*
X-692638Y72138D01*
G01D02*
X-692678Y72363D01*
G01D02*
X-692758Y72513D01*
G01D02*
X-692898Y72625D01*
G01D02*
X-693438D01*
G01X-692518Y71013D02*
X-692558Y71275D01*
G01D02*
X-692678Y71500D01*
G01D02*
X-692818Y71575D01*
G01D02*
X-693438D01*
G01X-692008Y72250D02*
X-691888Y72475D01*
G01D02*
X-691748Y72588D01*
G01D02*
X-691588Y72625D01*
G01D02*
X-691388Y72550D01*
G01D02*
X-691248Y72363D01*
G01D02*
X-691208Y72138D01*
G01D02*
X-691228Y71913D01*
G01D02*
X-691308Y71725D01*
G01D02*
X-691708Y71350D01*
G01D02*
X-691888Y71088D01*
G01X-671333Y74706D02*
X-683169D01*
G01X-685010Y129213D02*
X-679104Y135118D01*
G01X-689581Y173459D02*
X-693431Y167959D01*
G01X-691506Y166959D02*
Y174459D01*
G01X-693431Y173459D02*
X-689581Y167959D01*
G01X-688881Y170709D02*
X-694131D01*
G01X-678531Y70530D02*
Y72780D01*
G01X-677221Y70829D02*
X-677061Y70642D01*
G01D02*
X-676881Y70530D01*
G01D02*
X-676721D01*
G01D02*
X-676561Y70642D01*
G01D02*
X-676441Y70829D01*
G01D02*
X-676381Y71092D01*
G01X-675831Y70867D02*
X-675871Y70530D01*
G01D02*
X-675031D01*
G01X-671333Y68753D02*
Y74706D01*
G01X-678531Y72780D02*
X-677771D01*
G01X-678051Y71692D02*
X-678531D01*
G01X-676381Y71092D02*
X-676421Y71354D01*
G01D02*
X-676521Y71580D01*
G01D02*
X-676701Y71730D01*
G01D02*
X-676941Y71805D01*
G01D02*
X-677081Y71954D01*
G01D02*
X-677141Y72217D01*
G01D02*
X-677101Y72480D01*
G01D02*
X-677001Y72667D01*
G01D02*
X-676861Y72780D01*
G01D02*
X-676721D01*
G01D02*
X-676581Y72705D01*
G01D02*
X-676461Y72517D01*
G01X-675831Y72405D02*
X-675711Y72630D01*
G01D02*
X-675571Y72742D01*
G01D02*
X-675411Y72780D01*
G01D02*
X-675211Y72705D01*
G01D02*
X-675071Y72517D01*
G01D02*
X-675031Y72292D01*
G01D02*
X-675051Y72067D01*
G01D02*
X-675131Y71880D01*
G01D02*
X-675531Y71505D01*
G01D02*
X-675711Y71242D01*
G01D02*
X-675831Y70867D01*
G01X-679104Y135118D02*
Y174685D01*
G01X-650667Y48425D02*
X-635608D01*
G01X-650667Y187973D02*
Y48425D01*
G01X-663750Y114626D02*
Y402343D01*
G01X-587774Y187973D02*
X-650667D01*
G01X-635608Y-128149D02*
X-602833D01*
G01X-635608Y48425D02*
Y-128149D01*
G01X-640370Y259103D02*
X-634417D01*
G01X-640370Y270905D02*
Y259103D01*
G01X-634417D02*
Y270905D01*
G01X-633620Y259103D02*
X-627667D01*
G01X-633620Y270905D02*
Y259103D01*
G01X-638423Y264094D02*
X-638535Y263974D01*
G01D02*
X-638610Y263834D01*
G01D02*
Y263674D01*
G01D02*
X-638498Y263494D01*
G01D02*
X-638310Y263354D01*
G01D02*
X-638085Y263254D01*
G01D02*
X-637710Y263174D01*
G01D02*
X-637373Y263154D01*
G01D02*
X-637035Y263194D01*
G01D02*
X-636810Y263254D01*
G01D02*
X-636585Y263374D01*
G01D02*
X-636435Y263514D01*
G01D02*
X-636360Y263654D01*
G01D02*
Y263794D01*
G01D02*
X-636435Y263934D01*
G01D02*
X-636548Y264054D01*
G01D02*
X-636698Y264154D01*
G01X-636810Y264564D02*
X-636548Y264684D01*
G01D02*
X-636398Y264844D01*
G01D02*
X-636360Y265024D01*
G01D02*
X-636398Y265184D01*
G01D02*
X-636585Y265344D01*
G01D02*
X-636810Y265444D01*
G01D02*
X-637035Y265464D01*
G01D02*
X-637298Y265424D01*
G01D02*
X-637485Y265284D01*
G01D02*
X-637560Y265144D01*
G01D02*
Y264964D01*
G01Y265144D02*
X-637673Y265264D01*
G01D02*
X-637860Y265364D01*
G01D02*
X-638085Y265404D01*
G01D02*
X-638310Y265364D01*
G01D02*
X-638498Y265264D01*
G01D02*
X-638610Y265084D01*
G01D02*
X-638573Y264904D01*
G01D02*
X-638423Y264724D01*
G01X-638610Y266354D02*
X-638535Y266194D01*
G01D02*
X-638348Y266074D01*
G01D02*
X-638123Y265994D01*
G01D02*
X-637823Y265934D01*
G01D02*
X-637485Y265914D01*
G01D02*
X-637148Y265934D01*
G01D02*
X-636848Y265994D01*
G01D02*
X-636623Y266074D01*
G01D02*
X-636435Y266194D01*
G01D02*
X-636360Y266354D01*
G01D02*
X-636435Y266514D01*
G01D02*
X-636623Y266634D01*
G01D02*
X-636848Y266714D01*
G01D02*
X-637148Y266774D01*
G01D02*
X-637485Y266794D01*
G01D02*
X-637823Y266774D01*
G01D02*
X-638123Y266714D01*
G01D02*
X-638348Y266634D01*
G01D02*
X-638535Y266514D01*
G01D02*
X-638610Y266354D01*
G01X-634417Y270905D02*
X-640370D01*
G01X-627667D02*
X-633620D01*
G01X-640178Y279728D02*
Y297831D01*
G01X-629425Y279728D02*
X-640178D01*
G01X-636249Y287870D02*
X-636362Y287750D01*
G01D02*
X-636437Y287610D01*
G01D02*
Y287450D01*
G01D02*
X-636324Y287270D01*
G01D02*
X-636137Y287130D01*
G01D02*
X-635912Y287030D01*
G01D02*
X-635537Y286950D01*
G01D02*
X-635200Y286930D01*
G01D02*
X-634862Y286970D01*
G01D02*
X-634637Y287030D01*
G01D02*
X-634412Y287150D01*
G01D02*
X-634262Y287290D01*
G01D02*
X-634187Y287430D01*
G01D02*
Y287570D01*
G01D02*
X-634262Y287710D01*
G01D02*
X-634374Y287830D01*
G01D02*
X-634524Y287930D01*
G01X-634637Y288340D02*
X-634374Y288460D01*
G01D02*
X-634224Y288620D01*
G01D02*
X-634187Y288800D01*
G01D02*
X-634224Y288960D01*
G01D02*
X-634412Y289120D01*
G01D02*
X-634637Y289220D01*
G01D02*
X-634862Y289240D01*
G01D02*
X-635124Y289200D01*
G01D02*
X-635312Y289060D01*
G01D02*
X-635387Y288920D01*
G01D02*
Y288740D01*
G01Y288920D02*
X-635500Y289040D01*
G01D02*
X-635687Y289140D01*
G01D02*
X-635912Y289180D01*
G01D02*
X-636137Y289140D01*
G01D02*
X-636324Y289040D01*
G01D02*
X-636437Y288860D01*
G01D02*
X-636400Y288680D01*
G01D02*
X-636249Y288500D01*
G01X-634187Y290090D02*
X-634674Y290130D01*
G01D02*
X-635087Y290190D01*
G01D02*
X-635462Y290270D01*
G01D02*
X-635874Y290370D01*
G01D02*
X-636437Y290530D01*
G01D02*
Y289730D01*
G01X-629425Y299978D02*
X-640178D01*
G01D02*
Y318081D01*
G01Y297831D02*
X-629425D01*
G01X-636156Y307196D02*
Y307036D01*
G01D02*
X-636044Y306856D01*
G01D02*
X-635856Y306716D01*
G01D02*
X-635631Y306616D01*
G01D02*
X-635256Y306536D01*
G01D02*
X-634919Y306516D01*
G01D02*
X-634581Y306556D01*
G01D02*
X-634356Y306616D01*
G01D02*
X-634131Y306736D01*
G01D02*
X-633981Y306876D01*
G01D02*
X-633906Y307016D01*
G01D02*
Y307156D01*
G01X-635969Y307456D02*
X-636081Y307336D01*
G01D02*
X-636156Y307196D01*
G01X-633906Y307156D02*
X-633981Y307296D01*
G01D02*
X-634094Y307416D01*
G01D02*
X-634244Y307516D01*
G01X-634356Y307926D02*
X-634094Y308046D01*
G01D02*
X-633944Y308206D01*
G01D02*
X-633906Y308386D01*
G01D02*
X-633944Y308546D01*
G01D02*
X-634131Y308706D01*
G01D02*
X-634356Y308806D01*
G01D02*
X-634581Y308826D01*
G01D02*
X-634844Y308786D01*
G01D02*
X-635031Y308646D01*
G01D02*
X-635106Y308506D01*
G01D02*
Y308326D01*
G01Y308506D02*
X-635219Y308626D01*
G01D02*
X-635406Y308726D01*
G01D02*
X-635631Y308766D01*
G01D02*
X-635856Y308726D01*
G01D02*
X-636044Y308626D01*
G01D02*
X-636156Y308446D01*
G01D02*
X-636119Y308266D01*
G01D02*
X-635969Y308086D01*
G01X-634244Y309276D02*
X-634056Y309396D01*
G01D02*
X-633944Y309536D01*
G01D02*
X-633906Y309716D01*
G01D02*
X-633981Y309896D01*
G01D02*
X-634131Y310036D01*
G01D02*
X-634394Y310136D01*
G01D02*
X-634694Y310156D01*
G01D02*
X-634994Y310116D01*
G01D02*
X-635181Y310016D01*
G01D02*
X-635331Y309876D01*
G01D02*
X-635369Y309736D01*
G01D02*
X-635331Y309596D01*
G01D02*
X-635181Y309416D01*
G01D02*
X-636156Y309476D01*
G01D02*
Y310016D01*
G01X-640178Y318081D02*
X-629425D01*
G01X-640178Y320228D02*
Y338331D01*
G01X-629425Y320228D02*
X-640178D01*
G01X-636249Y328370D02*
X-636362Y328250D01*
G01D02*
X-636437Y328110D01*
G01D02*
Y327950D01*
G01D02*
X-636324Y327770D01*
G01D02*
X-636137Y327630D01*
G01D02*
X-635912Y327530D01*
G01D02*
X-635537Y327450D01*
G01D02*
X-635200Y327430D01*
G01D02*
X-634862Y327470D01*
G01D02*
X-634637Y327530D01*
G01D02*
X-634412Y327650D01*
G01D02*
X-634262Y327790D01*
G01D02*
X-634187Y327930D01*
G01D02*
Y328070D01*
G01D02*
X-634262Y328210D01*
G01D02*
X-634374Y328330D01*
G01D02*
X-634524Y328430D01*
G01X-634637Y328840D02*
X-634374Y328960D01*
G01D02*
X-634224Y329120D01*
G01D02*
X-634187Y329300D01*
G01D02*
X-634224Y329460D01*
G01D02*
X-634412Y329620D01*
G01D02*
X-634637Y329720D01*
G01D02*
X-634862Y329740D01*
G01D02*
X-635124Y329700D01*
G01D02*
X-635312Y329560D01*
G01D02*
X-635387Y329420D01*
G01D02*
Y329240D01*
G01Y329420D02*
X-635500Y329540D01*
G01D02*
X-635687Y329640D01*
G01D02*
X-635912Y329680D01*
G01D02*
X-636137Y329640D01*
G01D02*
X-636324Y329540D01*
G01D02*
X-636437Y329360D01*
G01D02*
X-636400Y329180D01*
G01D02*
X-636249Y329000D01*
G01X-635124Y330250D02*
X-635387Y330390D01*
G01D02*
X-635537Y330510D01*
G01D02*
X-635612Y330670D01*
G01D02*
X-635537Y330810D01*
G01D02*
X-635387Y330910D01*
G01D02*
X-635162Y330990D01*
G01D02*
X-634900Y331010D01*
G01D02*
X-634674Y330990D01*
G01D02*
X-634449Y330910D01*
G01D02*
X-634262Y330790D01*
G01D02*
X-634187Y330650D01*
G01D02*
X-634262Y330490D01*
G01D02*
X-634487Y330350D01*
G01D02*
X-634825Y330270D01*
G01D02*
X-635200Y330250D01*
G01D02*
X-635687Y330290D01*
G01D02*
X-635950Y330350D01*
G01D02*
X-636212Y330450D01*
G01D02*
X-636400Y330590D01*
G01D02*
X-636437Y330730D01*
G01D02*
X-636362Y330870D01*
G01D02*
X-636174Y330970D01*
G01X-640178Y338331D02*
X-629425D01*
G01X-635978Y348620D02*
X-636090Y348500D01*
G01D02*
X-636165Y348360D01*
G01D02*
Y348200D01*
G01D02*
X-636053Y348020D01*
G01D02*
X-635865Y347880D01*
G01D02*
X-635640Y347780D01*
G01D02*
X-635265Y347700D01*
G01D02*
X-634928Y347680D01*
G01D02*
X-634590Y347720D01*
G01D02*
X-634365Y347780D01*
G01D02*
X-634140Y347900D01*
G01D02*
X-633990Y348040D01*
G01D02*
X-633915Y348180D01*
G01D02*
Y348320D01*
G01D02*
X-633990Y348460D01*
G01D02*
X-634103Y348580D01*
G01D02*
X-634253Y348680D01*
G01X-634365Y349090D02*
X-634103Y349210D01*
G01D02*
X-633953Y349370D01*
G01D02*
X-633915Y349550D01*
G01D02*
X-633953Y349710D01*
G01D02*
X-634140Y349870D01*
G01D02*
X-634365Y349970D01*
G01D02*
X-634590Y349990D01*
G01D02*
X-634853Y349950D01*
G01D02*
X-635040Y349810D01*
G01D02*
X-635115Y349670D01*
G01D02*
Y349490D01*
G01Y349670D02*
X-635228Y349790D01*
G01D02*
X-635415Y349890D01*
G01D02*
X-635640Y349930D01*
G01D02*
X-635865Y349890D01*
G01D02*
X-636053Y349790D01*
G01D02*
X-636165Y349610D01*
G01D02*
X-636128Y349430D01*
G01D02*
X-635978Y349250D01*
G01X-633915Y350880D02*
X-633953Y351020D01*
G01D02*
X-634065Y351180D01*
G01D02*
X-634253Y351280D01*
G01D02*
X-634515Y351320D01*
G01D02*
X-634778Y351280D01*
G01D02*
X-635003Y351160D01*
G01D02*
X-635115Y350980D01*
G01D02*
Y350780D01*
G01D02*
X-635190Y350660D01*
G01D02*
X-635378Y350560D01*
G01D02*
X-635640Y350520D01*
G01D02*
X-635903Y350580D01*
G01D02*
X-636090Y350720D01*
G01D02*
X-636165Y350880D01*
G01D02*
X-636090Y351040D01*
G01D02*
X-635903Y351180D01*
G01D02*
X-635640Y351240D01*
G01D02*
X-635378Y351200D01*
G01D02*
X-635190Y351100D01*
G01D02*
X-635115Y350980D01*
G01D02*
Y350780D01*
G01D02*
X-635003Y350600D01*
G01D02*
X-634778Y350480D01*
G01D02*
X-634515Y350440D01*
G01D02*
X-634253Y350480D01*
G01D02*
X-634065Y350580D01*
G01D02*
X-633953Y350740D01*
G01D02*
X-633915Y350880D01*
G01X-629425Y340478D02*
X-640178D01*
G01D02*
Y358581D01*
G01D02*
X-629425D01*
G01X-617296Y126982D02*
X-621146Y121482D01*
G01X-619221Y120482D02*
Y127982D01*
G01X-621146Y126982D02*
X-617296Y121482D01*
G01X-616596Y124232D02*
X-621846D01*
G01X-629683Y165417D02*
X-629246Y164667D01*
G01D02*
X-628721Y164167D01*
G01D02*
X-628108Y163917D01*
G01D02*
X-627408Y164167D01*
G01D02*
X-626883Y164667D01*
G01D02*
X-626358Y165417D01*
G01X-620433Y163917D02*
Y171417D01*
G01X-621483Y163917D02*
X-619383D01*
G01X-626358Y165417D02*
X-626183Y166417D01*
G01D02*
Y171417D01*
G01X-620433D02*
X-621483Y169917D01*
G01X-626059Y258128D02*
Y265880D01*
G01X-611229Y258128D02*
X-626059D01*
G01X-627667Y259103D02*
Y270905D01*
G01X-631673Y264094D02*
X-631785Y263974D01*
G01D02*
X-631860Y263834D01*
G01D02*
Y263674D01*
G01D02*
X-631748Y263494D01*
G01D02*
X-631560Y263354D01*
G01D02*
X-631335Y263254D01*
G01D02*
X-630960Y263174D01*
G01D02*
X-630623Y263154D01*
G01D02*
X-630285Y263194D01*
G01D02*
X-630060Y263254D01*
G01D02*
X-629835Y263374D01*
G01D02*
X-629685Y263514D01*
G01D02*
X-629610Y263654D01*
G01D02*
Y263794D01*
G01D02*
X-629685Y263934D01*
G01D02*
X-629798Y264054D01*
G01D02*
X-629948Y264154D01*
G01X-631485Y264624D02*
X-631710Y264744D01*
G01D02*
X-631823Y264884D01*
G01D02*
X-631860Y265044D01*
G01D02*
X-631785Y265244D01*
G01D02*
X-631598Y265384D01*
G01D02*
X-631373Y265424D01*
G01D02*
X-631148Y265404D01*
G01D02*
X-630960Y265324D01*
G01D02*
X-630585Y264924D01*
G01D02*
X-630323Y264744D01*
G01D02*
X-629948Y264624D01*
G01D02*
X-629610Y264584D01*
G01D02*
Y265424D01*
G01X-629873Y266014D02*
X-629685Y266154D01*
G01D02*
X-629610Y266314D01*
G01D02*
X-629685Y266474D01*
G01D02*
X-629910Y266614D01*
G01D02*
X-630248Y266714D01*
G01D02*
X-630585Y266754D01*
G01D02*
X-630998D01*
G01D02*
X-631335Y266714D01*
G01D02*
X-631635Y266614D01*
G01D02*
X-631785Y266494D01*
G01D02*
X-631860Y266354D01*
G01D02*
X-631785Y266194D01*
G01D02*
X-631635Y266074D01*
G01D02*
X-631410Y265994D01*
G01D02*
X-631110Y265954D01*
G01D02*
X-630848Y265994D01*
G01D02*
X-630585Y266094D01*
G01D02*
X-630435Y266214D01*
G01D02*
X-630398Y266354D01*
G01D02*
X-630473Y266514D01*
G01D02*
X-630660Y266634D01*
G01D02*
X-630998Y266754D01*
G01X-621912Y270187D02*
X-624162D01*
G01D02*
Y270947D01*
G01X-623074Y270667D02*
Y270187D01*
G01X-623112Y272077D02*
X-623224Y272157D01*
G01D02*
X-623412Y272217D01*
G01D02*
X-623674Y272257D01*
G01D02*
X-623899Y272217D01*
G01D02*
X-624049Y272137D01*
G01D02*
X-624162Y271997D01*
G01D02*
Y271457D01*
G01D02*
X-621912D01*
G01D02*
Y272117D01*
G01D02*
X-622062Y272257D01*
G01D02*
X-622287Y272337D01*
G01D02*
X-622549Y272377D01*
G01D02*
X-622812Y272337D01*
G01D02*
X-623037Y272217D01*
G01D02*
X-623112Y272077D01*
G01D02*
Y271457D01*
G01X-621912Y273267D02*
X-624162D01*
G01D02*
X-623712Y273027D01*
G01X-621912D02*
Y273507D01*
G01X-624162Y274617D02*
X-624087Y274457D01*
G01D02*
X-623899Y274337D01*
G01D02*
X-623674Y274257D01*
G01D02*
X-623374Y274197D01*
G01D02*
X-623037Y274177D01*
G01D02*
X-622699Y274197D01*
G01D02*
X-622399Y274257D01*
G01D02*
X-622174Y274337D01*
G01D02*
X-621987Y274457D01*
G01D02*
X-621912Y274617D01*
G01D02*
X-621987Y274777D01*
G01D02*
X-622174Y274897D01*
G01D02*
X-622399Y274977D01*
G01D02*
X-622699Y275037D01*
G01D02*
X-623037Y275057D01*
G01D02*
X-623374Y275037D01*
G01D02*
X-623674Y274977D01*
G01D02*
X-623899Y274897D01*
G01D02*
X-624087Y274777D01*
G01D02*
X-624162Y274617D01*
G01X-626144Y266504D02*
X-620144D01*
G01X-626144Y278504D02*
Y266504D01*
G01X-620144D02*
Y278504D01*
G01X-616778Y266662D02*
X-610825D01*
G01X-616778Y278497D02*
Y266662D01*
G01X-620394Y260823D02*
Y263073D01*
G01D02*
X-619894D01*
G01D02*
X-619734Y262960D01*
G01D02*
X-619634Y262810D01*
G01D02*
X-619594Y262510D01*
G01D02*
X-619634Y262210D01*
G01D02*
X-619754Y262023D01*
G01D02*
X-619894Y261910D01*
G01D02*
X-620394D01*
G01X-619894D02*
X-619594Y260823D01*
G01X-618684D02*
X-618644Y261310D01*
G01D02*
X-618584Y261723D01*
G01D02*
X-618504Y262098D01*
G01D02*
X-618404Y262510D01*
G01D02*
X-618244Y263073D01*
G01D02*
X-619044D01*
G01X-617054Y260823D02*
Y263073D01*
G01D02*
X-617794Y261460D01*
G01D02*
X-616794D01*
G01X-626059Y265880D02*
X-611229D01*
G01X-629425Y297831D02*
Y279728D01*
G01X-628778Y283628D02*
X-622825D01*
G01X-628778Y295431D02*
Y283628D01*
G01X-620144Y278504D02*
X-626144D01*
G01X-610825Y278497D02*
X-616778D01*
G01X-626640Y288797D02*
X-626752Y288677D01*
G01D02*
X-626827Y288537D01*
G01D02*
Y288377D01*
G01D02*
X-626715Y288197D01*
G01D02*
X-626527Y288057D01*
G01D02*
X-626302Y287957D01*
G01D02*
X-625927Y287877D01*
G01D02*
X-625590Y287857D01*
G01D02*
X-625252Y287897D01*
G01D02*
X-625027Y287957D01*
G01D02*
X-624802Y288077D01*
G01D02*
X-624652Y288217D01*
G01D02*
X-624577Y288357D01*
G01D02*
Y288497D01*
G01D02*
X-624652Y288637D01*
G01D02*
X-624765Y288757D01*
G01D02*
X-624915Y288857D01*
G01X-625027Y289267D02*
X-624765Y289387D01*
G01D02*
X-624615Y289547D01*
G01D02*
X-624577Y289727D01*
G01D02*
X-624615Y289887D01*
G01D02*
X-624802Y290047D01*
G01D02*
X-625027Y290147D01*
G01D02*
X-625252Y290167D01*
G01D02*
X-625515Y290127D01*
G01D02*
X-625702Y289987D01*
G01D02*
X-625777Y289847D01*
G01D02*
Y289667D01*
G01Y289847D02*
X-625890Y289967D01*
G01D02*
X-626077Y290067D01*
G01D02*
X-626302Y290107D01*
G01D02*
X-626527Y290067D01*
G01D02*
X-626715Y289967D01*
G01D02*
X-626827Y289787D01*
G01D02*
X-626790Y289607D01*
G01D02*
X-626640Y289427D01*
G01X-624577Y291057D02*
X-626827D01*
G01D02*
X-626377Y290817D01*
G01X-624577D02*
Y291297D01*
G01X-622825Y283628D02*
Y295431D01*
G01X-621216Y287903D02*
Y295656D01*
G01X-606386Y287903D02*
X-621216D01*
G01X-628778Y302378D02*
X-622825D01*
G01X-628778Y314181D02*
Y302378D01*
G01X-622825Y295431D02*
X-628778D01*
G01X-629425Y318081D02*
Y299978D01*
G01X-622825Y302378D02*
Y314181D01*
G01X-617118Y297476D02*
Y299726D01*
G01D02*
X-616358D01*
G01X-616638Y298638D02*
X-617118D01*
G01X-621301Y295680D02*
X-609301D01*
G01X-621301Y301680D02*
Y295680D01*
G01X-609301Y301680D02*
X-621301D01*
G01X-621369Y311256D02*
Y305303D01*
G01D02*
X-609533D01*
G01X-621216Y295656D02*
X-606386D01*
G01X-627018Y307110D02*
Y306950D01*
G01D02*
X-626905Y306770D01*
G01D02*
X-626718Y306630D01*
G01D02*
X-626493Y306530D01*
G01D02*
X-626118Y306450D01*
G01D02*
X-625780Y306430D01*
G01D02*
X-625443Y306470D01*
G01D02*
X-625218Y306530D01*
G01D02*
X-624993Y306650D01*
G01D02*
X-624843Y306790D01*
G01D02*
X-624768Y306930D01*
G01D02*
Y307070D01*
G01D02*
X-624843Y307210D01*
G01X-617031Y306780D02*
Y309030D01*
G01X-622825Y314181D02*
X-628778D01*
G01X-629425Y338331D02*
Y320228D01*
G01X-626830Y307370D02*
X-626943Y307250D01*
G01D02*
X-627018Y307110D01*
G01X-624843Y307210D02*
X-624955Y307330D01*
G01D02*
X-625105Y307430D01*
G01X-625218Y307840D02*
X-624955Y307960D01*
G01D02*
X-624805Y308120D01*
G01D02*
X-624768Y308300D01*
G01D02*
X-624805Y308460D01*
G01D02*
X-624993Y308620D01*
G01D02*
X-625218Y308720D01*
G01D02*
X-625443Y308740D01*
G01D02*
X-625705Y308700D01*
G01D02*
X-625893Y308560D01*
G01D02*
X-625968Y308420D01*
G01D02*
Y308240D01*
G01Y308420D02*
X-626080Y308540D01*
G01D02*
X-626268Y308640D01*
G01D02*
X-626493Y308680D01*
G01D02*
X-626718Y308640D01*
G01D02*
X-626905Y308540D01*
G01D02*
X-627018Y308360D01*
G01D02*
X-626980Y308180D01*
G01D02*
X-626830Y308000D01*
G01X-625218Y309190D02*
X-624955Y309310D01*
G01D02*
X-624805Y309470D01*
G01D02*
X-624768Y309650D01*
G01D02*
X-624805Y309810D01*
G01D02*
X-624993Y309970D01*
G01D02*
X-625218Y310070D01*
G01D02*
X-625443Y310090D01*
G01D02*
X-625705Y310050D01*
G01D02*
X-625893Y309910D01*
G01D02*
X-625968Y309770D01*
G01D02*
Y309590D01*
G01Y309770D02*
X-626080Y309890D01*
G01D02*
X-626268Y309990D01*
G01D02*
X-626493Y310030D01*
G01D02*
X-626718Y309990D01*
G01D02*
X-626905Y309890D01*
G01D02*
X-627018Y309710D01*
G01D02*
X-626980Y309530D01*
G01D02*
X-626830Y309350D01*
G01X-621695Y311378D02*
Y322130D01*
G01X-603592Y311378D02*
X-621695D01*
G01Y322130D02*
X-603592D01*
G01X-617031Y309030D02*
X-616271D01*
G01X-616551Y307942D02*
X-617031D01*
G01X-609533Y311256D02*
X-621369D01*
G01X-628778Y324128D02*
X-622825D01*
G01X-628778Y335931D02*
Y324128D01*
G01X-622825Y335931D02*
X-628778D01*
G01X-626780Y328920D02*
X-626892Y328800D01*
G01D02*
X-626967Y328660D01*
G01D02*
Y328500D01*
G01D02*
X-626855Y328320D01*
G01D02*
X-626667Y328180D01*
G01D02*
X-626442Y328080D01*
G01D02*
X-626067Y328000D01*
G01D02*
X-625730Y327980D01*
G01D02*
X-625392Y328020D01*
G01D02*
X-625167Y328080D01*
G01D02*
X-624942Y328200D01*
G01D02*
X-624792Y328340D01*
G01D02*
X-624717Y328480D01*
G01D02*
Y328620D01*
G01D02*
X-624792Y328760D01*
G01D02*
X-624905Y328880D01*
G01D02*
X-625055Y328980D01*
G01X-625167Y329390D02*
X-624905Y329510D01*
G01D02*
X-624755Y329670D01*
G01D02*
X-624717Y329850D01*
G01D02*
X-624755Y330010D01*
G01D02*
X-624942Y330170D01*
G01D02*
X-625167Y330270D01*
G01D02*
X-625392Y330290D01*
G01D02*
X-625655Y330250D01*
G01D02*
X-625842Y330110D01*
G01D02*
X-625917Y329970D01*
G01D02*
Y329790D01*
G01Y329970D02*
X-626030Y330090D01*
G01D02*
X-626217Y330190D01*
G01D02*
X-626442Y330230D01*
G01D02*
X-626667Y330190D01*
G01D02*
X-626855Y330090D01*
G01D02*
X-626967Y329910D01*
G01D02*
X-626930Y329730D01*
G01D02*
X-626780Y329550D01*
G01X-626592Y330800D02*
X-626817Y330920D01*
G01D02*
X-626930Y331060D01*
G01D02*
X-626967Y331220D01*
G01D02*
X-626892Y331420D01*
G01D02*
X-626705Y331560D01*
G01D02*
X-626480Y331600D01*
G01D02*
X-626255Y331580D01*
G01D02*
X-626067Y331500D01*
G01D02*
X-625692Y331100D01*
G01D02*
X-625430Y330920D01*
G01D02*
X-625055Y330800D01*
G01D02*
X-624717Y330760D01*
G01D02*
Y331600D01*
G01X-622825Y324128D02*
Y335931D01*
G01X-621216Y328403D02*
Y336156D01*
G01X-606386Y328403D02*
X-621216D01*
G01X-621301Y336180D02*
X-609301D01*
G01X-621301Y342180D02*
Y336180D01*
G01X-621216Y336156D02*
X-606386D01*
G01X-628778Y342878D02*
X-622825D01*
G01X-628778Y354681D02*
Y342878D01*
G01X-629425Y358581D02*
Y340478D01*
G01X-626830Y347870D02*
X-626943Y347750D01*
G01D02*
X-627018Y347610D01*
G01D02*
Y347450D01*
G01D02*
X-626905Y347270D01*
G01D02*
X-626718Y347130D01*
G01D02*
X-626493Y347030D01*
G01D02*
X-626118Y346950D01*
G01D02*
X-625780Y346930D01*
G01D02*
X-625443Y346970D01*
G01D02*
X-625218Y347030D01*
G01D02*
X-624993Y347150D01*
G01D02*
X-624843Y347290D01*
G01D02*
X-624768Y347430D01*
G01D02*
Y347570D01*
G01D02*
X-624843Y347710D01*
G01D02*
X-624955Y347830D01*
G01D02*
X-625105Y347930D01*
G01X-625218Y348340D02*
X-624955Y348459D01*
G01D02*
X-624805Y348620D01*
G01D02*
X-624768Y348800D01*
G01D02*
X-624805Y348960D01*
G01D02*
X-624993Y349120D01*
G01D02*
X-625218Y349220D01*
G01D02*
X-625443Y349240D01*
G01D02*
X-625705Y349200D01*
G01D02*
X-625893Y349060D01*
G01D02*
X-625968Y348920D01*
G01D02*
Y348740D01*
G01Y348920D02*
X-626080Y349040D01*
G01D02*
X-626268Y349140D01*
G01D02*
X-626493Y349180D01*
G01D02*
X-626718Y349140D01*
G01D02*
X-626905Y349040D01*
G01D02*
X-627018Y348860D01*
G01D02*
X-626980Y348680D01*
G01D02*
X-626830Y348500D01*
G01X-624768Y350370D02*
X-627018D01*
G01D02*
X-625405Y349630D01*
G01D02*
Y350630D01*
G01X-622825Y342878D02*
Y354681D01*
G01X-609301Y342180D02*
X-621301D01*
G01X-621219Y350256D02*
Y344303D01*
G01X-609383Y350256D02*
X-621219D01*
G01Y344303D02*
X-609383D01*
G01X-622825Y354681D02*
X-628778D01*
G01X-602833Y-128149D02*
Y48425D01*
G01D02*
X-587774D01*
G01X-614508Y165542D02*
X-614158Y164792D01*
G01D02*
X-613633Y164167D01*
G01D02*
X-612933Y163917D01*
G01D02*
X-612233Y164167D01*
G01D02*
X-611708Y164792D01*
G01D02*
X-611358Y165542D01*
G01X-612933Y171417D02*
X-613633Y171167D01*
G01D02*
X-614158Y170542D01*
G01D02*
X-614508Y169792D01*
G01D02*
X-614771Y168792D01*
G01D02*
X-614858Y167667D01*
G01D02*
X-614771Y166542D01*
G01D02*
X-614508Y165542D01*
G01X-611358D02*
X-611096Y166542D01*
G01D02*
X-611008Y167667D01*
G01D02*
X-611096Y168792D01*
G01D02*
X-611358Y169792D01*
G01D02*
X-611708Y170542D01*
G01D02*
X-612233Y171167D01*
G01D02*
X-612933Y171417D01*
G01X-611229Y265880D02*
Y258128D01*
G01X-612823Y269421D02*
X-615073D01*
G01D02*
Y270181D01*
G01X-613985Y269901D02*
Y269421D01*
G01X-613123Y270731D02*
X-612935Y270891D01*
G01D02*
X-612823Y271071D01*
G01D02*
Y271231D01*
G01D02*
X-612935Y271391D01*
G01D02*
X-613123Y271511D01*
G01D02*
X-613385Y271571D01*
G01D02*
X-613648Y271531D01*
G01D02*
X-613873Y271431D01*
G01D02*
X-614023Y271251D01*
G01D02*
X-614098Y271011D01*
G01D02*
X-614248Y270871D01*
G01D02*
X-614510Y270811D01*
G01D02*
X-614773Y270851D01*
G01D02*
X-614960Y270951D01*
G01D02*
X-615073Y271091D01*
G01D02*
Y271231D01*
G01D02*
X-614998Y271371D01*
G01D02*
X-614810Y271491D01*
G01X-612823Y272501D02*
X-615073D01*
G01D02*
X-614623Y272261D01*
G01X-612823D02*
Y272741D01*
G01X-615073Y273851D02*
X-614998Y273691D01*
G01D02*
X-614810Y273571D01*
G01D02*
X-614585Y273491D01*
G01D02*
X-614285Y273431D01*
G01D02*
X-613948Y273411D01*
G01D02*
X-613610Y273431D01*
G01D02*
X-613310Y273491D01*
G01D02*
X-613085Y273571D01*
G01D02*
X-612898Y273691D01*
G01D02*
X-612823Y273851D01*
G01D02*
X-612898Y274011D01*
G01D02*
X-613085Y274131D01*
G01D02*
X-613310Y274211D01*
G01D02*
X-613610Y274271D01*
G01D02*
X-613948Y274291D01*
G01D02*
X-614285Y274271D01*
G01D02*
X-614585Y274211D01*
G01D02*
X-614810Y274131D01*
G01D02*
X-614998Y274011D01*
G01D02*
X-615073Y273851D01*
G01X-610825Y266662D02*
Y278497D01*
G01X-615455Y290479D02*
Y292729D01*
G01X-614955Y291566D02*
X-614655Y290479D01*
G01X-613745D02*
X-613705Y290966D01*
G01D02*
X-613645Y291379D01*
G01X-612435Y291454D02*
X-612615Y291191D01*
G01D02*
X-612735Y290816D01*
G01D02*
X-612775Y290479D01*
G01D02*
X-611935D01*
G01X-606386Y295656D02*
Y287903D01*
G01X-615228Y298676D02*
X-615148Y298788D01*
G01D02*
X-615088Y298976D01*
G01D02*
X-615048Y299238D01*
G01D02*
X-615088Y299463D01*
G01D02*
X-615168Y299613D01*
G01D02*
X-615308Y299726D01*
G01D02*
X-615848D01*
G01D02*
Y297476D01*
G01D02*
X-615188D01*
G01D02*
X-615048Y297626D01*
G01D02*
X-614968Y297851D01*
G01D02*
X-614928Y298113D01*
G01D02*
X-614968Y298376D01*
G01D02*
X-615088Y298601D01*
G01D02*
X-615228Y298676D01*
G01D02*
X-615848D01*
G01X-614038Y297476D02*
X-613898Y297513D01*
G01D02*
X-613738Y297626D01*
G01D02*
X-613638Y297813D01*
G01D02*
X-613598Y298076D01*
G01D02*
X-613638Y298338D01*
G01D02*
X-613758Y298563D01*
G01D02*
X-613938Y298676D01*
G01D02*
X-614138D01*
G01D02*
X-614258Y298751D01*
G01D02*
X-614358Y298938D01*
G01D02*
X-614398Y299201D01*
G01D02*
X-614338Y299463D01*
G01D02*
X-614198Y299651D01*
G01D02*
X-614038Y299726D01*
G01D02*
X-613878Y299651D01*
G01D02*
X-613738Y299463D01*
G01D02*
X-613678Y299201D01*
G01D02*
X-613718Y298938D01*
G01D02*
X-613818Y298751D01*
G01D02*
X-613938Y298676D01*
G01D02*
X-614138D01*
G01D02*
X-614318Y298563D01*
G01D02*
X-614438Y298338D01*
G01D02*
X-614478Y298076D01*
G01D02*
X-614438Y297813D01*
G01D02*
X-614338Y297626D01*
G01D02*
X-614178Y297513D01*
G01D02*
X-614038Y297476D01*
G01X-609301Y295680D02*
Y301680D01*
G01X-609533Y305303D02*
Y311256D01*
G01X-615455Y292729D02*
X-614955D01*
G01D02*
X-614795Y292616D01*
G01D02*
X-614695Y292466D01*
G01D02*
X-614655Y292166D01*
G01D02*
X-614695Y291866D01*
G01D02*
X-614815Y291679D01*
G01D02*
X-614955Y291566D01*
G01D02*
X-615455D01*
G01X-613645Y291379D02*
X-613565Y291754D01*
G01D02*
X-613465Y292166D01*
G01D02*
X-613305Y292729D01*
G01D02*
X-614105D01*
G01X-612735Y292354D02*
X-612615Y292579D01*
G01D02*
X-612475Y292691D01*
G01D02*
X-612315Y292729D01*
G01D02*
X-612115Y292654D01*
G01D02*
X-611975Y292466D01*
G01D02*
X-611935Y292241D01*
G01D02*
X-611955Y292016D01*
G01D02*
X-612035Y291829D01*
G01D02*
X-612435Y291454D01*
G01X-615721Y307079D02*
X-615561Y306892D01*
G01D02*
X-615381Y306780D01*
G01D02*
X-615221D01*
G01D02*
X-615061Y306892D01*
G01D02*
X-614941Y307079D01*
G01D02*
X-614881Y307342D01*
G01X-613951Y306780D02*
X-613811Y306817D01*
G01D02*
X-613651Y306930D01*
G01D02*
X-613551Y307117D01*
G01X-614351D02*
X-614251Y306930D01*
G01D02*
X-614091Y306817D01*
G01D02*
X-613951Y306780D01*
G01X-613554Y317931D02*
X-613674Y318043D01*
G01D02*
X-613814Y318118D01*
G01D02*
X-613974D01*
G01D02*
X-614154Y318006D01*
G01D02*
X-614294Y317818D01*
G01D02*
X-614394Y317593D01*
G01D02*
X-614474Y317218D01*
G01D02*
X-614494Y316881D01*
G01D02*
X-614454Y316543D01*
G01D02*
X-614394Y316318D01*
G01D02*
X-614274Y316093D01*
G01D02*
X-614134Y315943D01*
G01D02*
X-613994Y315868D01*
G01D02*
X-613854D01*
G01D02*
X-613714Y315943D01*
G01D02*
X-613594Y316056D01*
G01D02*
X-613494Y316206D01*
G01X-613084Y316318D02*
X-612964Y316056D01*
G01D02*
X-612804Y315906D01*
G01D02*
X-612624Y315868D01*
G01D02*
X-612464Y315906D01*
G01D02*
X-612304Y316093D01*
G01D02*
X-612204Y316318D01*
G01D02*
X-612184Y316543D01*
G01D02*
X-612224Y316806D01*
G01D02*
X-612364Y316993D01*
G01D02*
X-612504Y317068D01*
G01D02*
X-612684D01*
G01X-612504D02*
X-612384Y317181D01*
G01D02*
X-612284Y317368D01*
G01D02*
X-612244Y317593D01*
G01D02*
X-612284Y317818D01*
G01D02*
X-612384Y318006D01*
G01D02*
X-612564Y318118D01*
G01D02*
X-612744Y318081D01*
G01D02*
X-612924Y317931D01*
G01X-611634Y316131D02*
X-611494Y315943D01*
G01D02*
X-611334Y315868D01*
G01D02*
X-611174Y315943D01*
G01D02*
X-611034Y316168D01*
G01D02*
X-610934Y316506D01*
G01D02*
X-610894Y316843D01*
G01D02*
Y317256D01*
G01D02*
X-610934Y317593D01*
G01D02*
X-611034Y317893D01*
G01D02*
X-611154Y318043D01*
G01D02*
X-611294Y318118D01*
G01D02*
X-611454Y318043D01*
G01D02*
X-611574Y317893D01*
G01D02*
X-611654Y317668D01*
G01D02*
X-611694Y317368D01*
G01D02*
X-611654Y317106D01*
G01D02*
X-611554Y316843D01*
G01D02*
X-611434Y316693D01*
G01D02*
X-611294Y316656D01*
G01D02*
X-611134Y316731D01*
G01D02*
X-611014Y316918D01*
G01D02*
X-610894Y317256D01*
G01X-614881Y307342D02*
X-614921Y307604D01*
G01D02*
X-615021Y307830D01*
G01D02*
X-615201Y307980D01*
G01D02*
X-615441Y308055D01*
G01D02*
X-615581Y308204D01*
G01D02*
X-615641Y308467D01*
G01D02*
X-615601Y308730D01*
G01D02*
X-615501Y308917D01*
G01D02*
X-615361Y309030D01*
G01D02*
X-615221D01*
G01D02*
X-615081Y308955D01*
G01D02*
X-614961Y308767D01*
G01X-613551Y307117D02*
X-613511Y307380D01*
G01D02*
X-613551Y307642D01*
G01D02*
X-613671Y307867D01*
G01D02*
X-613851Y307980D01*
G01D02*
X-614051D01*
G01D02*
X-614171Y308055D01*
G01D02*
X-614271Y308242D01*
G01D02*
X-614311Y308504D01*
G01D02*
X-614251Y308767D01*
G01D02*
X-614111Y308955D01*
G01D02*
X-613951Y309030D01*
G01D02*
X-613791Y308955D01*
G01D02*
X-613651Y308767D01*
G01D02*
X-613591Y308504D01*
G01D02*
X-613631Y308242D01*
G01D02*
X-613731Y308055D01*
G01D02*
X-613851Y307980D01*
G01D02*
X-614051D01*
G01D02*
X-614231Y307867D01*
G01D02*
X-614351Y307642D01*
G01D02*
X-614391Y307380D01*
G01D02*
X-614351Y307117D01*
G01X-603592Y322130D02*
Y311378D01*
G01X-606386Y336156D02*
Y328403D01*
G01X-616697Y338160D02*
Y340410D01*
G01X-615427D02*
Y338160D01*
G01D02*
X-614767D01*
G01D02*
X-614627Y338310D01*
G01D02*
X-614547Y338535D01*
G01D02*
X-614507Y338797D01*
G01X-613957Y338422D02*
X-613817Y338235D01*
G01D02*
X-613657Y338160D01*
G01D02*
X-613497Y338235D01*
G01D02*
X-613357Y338459D01*
G01D02*
X-613257Y338797D01*
G01X-609301Y336180D02*
Y342180D01*
G01X-615315Y330742D02*
Y332992D01*
G01D02*
X-614815D01*
G01D02*
X-614655Y332879D01*
G01D02*
X-614554Y332729D01*
G01D02*
X-614515Y332429D01*
G01D02*
X-614554Y332129D01*
G01D02*
X-614675Y331942D01*
G01D02*
X-614815Y331829D01*
G01D02*
X-615315D01*
G01X-614815D02*
X-614515Y330742D01*
G01X-613605D02*
X-613565Y331229D01*
G01D02*
X-613505Y331641D01*
G01D02*
X-613425Y332016D01*
G01D02*
X-613325Y332429D01*
G01D02*
X-613165Y332992D01*
G01D02*
X-613965D01*
G01X-612655Y331191D02*
X-612535Y330929D01*
G01D02*
X-612375Y330779D01*
G01D02*
X-612195Y330742D01*
G01D02*
X-612034Y330779D01*
G01D02*
X-611874Y330966D01*
G01D02*
X-611775Y331191D01*
G01D02*
X-611755Y331416D01*
G01D02*
X-611795Y331679D01*
G01D02*
X-611935Y331866D01*
G01D02*
X-612075Y331942D01*
G01D02*
X-612255D01*
G01X-612075D02*
X-611955Y332054D01*
G01D02*
X-611854Y332241D01*
G01D02*
X-611815Y332466D01*
G01D02*
X-611854Y332692D01*
G01D02*
X-611955Y332879D01*
G01D02*
X-612135Y332992D01*
G01D02*
X-612315Y332954D01*
G01D02*
X-612495Y332804D01*
G01X-616697Y340410D02*
X-615937D01*
G01X-616217Y339322D02*
X-616697D01*
G01X-614807Y339360D02*
X-614727Y339472D01*
G01D02*
X-614667Y339659D01*
G01D02*
X-614627Y339922D01*
G01D02*
X-614667Y340147D01*
G01D02*
X-614747Y340297D01*
G01D02*
X-614887Y340410D01*
G01D02*
X-615427D01*
G01X-614507Y338797D02*
X-614547Y339059D01*
G01D02*
X-614667Y339284D01*
G01D02*
X-614807Y339360D01*
G01D02*
X-615427D01*
G01X-613257Y338797D02*
X-613217Y339135D01*
G01D02*
Y339547D01*
G01D02*
X-613257Y339884D01*
G01D02*
X-613357Y340185D01*
G01D02*
X-613477Y340335D01*
G01D02*
X-613617Y340410D01*
G01D02*
X-613777Y340335D01*
G01D02*
X-613897Y340185D01*
G01D02*
X-613977Y339960D01*
G01D02*
X-614017Y339659D01*
G01D02*
X-613977Y339397D01*
G01D02*
X-613877Y339135D01*
G01D02*
X-613757Y338984D01*
G01D02*
X-613617Y338947D01*
G01D02*
X-613457Y339022D01*
G01D02*
X-613337Y339210D01*
G01D02*
X-613217Y339547D01*
G01X-616281Y345780D02*
Y348030D01*
G01D02*
X-615521D01*
G01X-615801Y346942D02*
X-616281D01*
G01X-614971Y346079D02*
X-614811Y345892D01*
G01D02*
X-614631Y345780D01*
G01D02*
X-614471D01*
G01D02*
X-614311Y345892D01*
G01D02*
X-614191Y346079D01*
G01D02*
X-614131Y346342D01*
G01D02*
X-614171Y346604D01*
G01D02*
X-614271Y346830D01*
G01D02*
X-614451Y346980D01*
G01D02*
X-614691Y347055D01*
G01D02*
X-614831Y347204D01*
G01D02*
X-614891Y347467D01*
G01D02*
X-614851Y347730D01*
G01D02*
X-614751Y347917D01*
G01D02*
X-614611Y348030D01*
G01D02*
X-614471D01*
G01D02*
X-614331Y347955D01*
G01D02*
X-614211Y347767D01*
G01X-613541Y346042D02*
X-613401Y345855D01*
G01D02*
X-613241Y345780D01*
G01D02*
X-613081Y345855D01*
G01D02*
X-612941Y346079D01*
G01D02*
X-612841Y346417D01*
G01D02*
X-612801Y346755D01*
G01D02*
Y347167D01*
G01D02*
X-612841Y347504D01*
G01D02*
X-612941Y347805D01*
G01D02*
X-613061Y347955D01*
G01D02*
X-613201Y348030D01*
G01D02*
X-613361Y347955D01*
G01D02*
X-613481Y347805D01*
G01D02*
X-613561Y347580D01*
G01D02*
X-613601Y347279D01*
G01D02*
X-613561Y347017D01*
G01D02*
X-613461Y346755D01*
G01D02*
X-613341Y346604D01*
G01D02*
X-613201Y346567D01*
G01D02*
X-613041Y346642D01*
G01D02*
X-612921Y346830D01*
G01D02*
X-612801Y347167D01*
G01X-609383Y344303D02*
Y350256D01*
G01X-587774Y48425D02*
Y187973D01*
G01X-580039Y182543D02*
X-448642D01*
G01X-580039Y406953D02*
Y182543D01*
G01X-448642Y406953D02*
X-580039D01*
G01X-569144Y2539D02*
X-498868D01*
G01X-569144Y163760D02*
Y2539D01*
G01X-498868Y163760D02*
X-569144D01*
G01X-541863Y146338D02*
X-541425Y145588D01*
G01D02*
X-540900Y145088D01*
G01D02*
X-540288Y144838D01*
G01D02*
X-539588Y145088D01*
G01D02*
X-539063Y145588D01*
G01D02*
X-538538Y146338D01*
G01D02*
X-538363Y147338D01*
G01D02*
Y152338D01*
G01X-532613Y144838D02*
Y152338D01*
G01X-533663Y144838D02*
X-531563D01*
G01X-525113D02*
Y152338D01*
G01X-526163Y144838D02*
X-524063D01*
G01X-532613Y152338D02*
X-533663Y150838D01*
G01X-525113Y152338D02*
X-526163Y150838D01*
G01X-523591Y288236D02*
X-523153Y287486D01*
G01D02*
X-522628Y286986D01*
G01D02*
X-522016Y286736D01*
G01X-501853Y73386D02*
X-507103D01*
G01X-522016Y286736D02*
X-521316Y286986D01*
G01D02*
X-520791Y287486D01*
G01D02*
X-520266Y288236D01*
G01D02*
X-520091Y289236D01*
G01D02*
Y294236D01*
G01X-514341Y286736D02*
Y294236D01*
G01X-515391Y286736D02*
X-513291D01*
G01X-505441Y291236D02*
X-507191Y289986D01*
G01D02*
X-507978Y289111D01*
G01D02*
X-508503Y287861D01*
G01D02*
X-508678Y286736D01*
G01D02*
X-505003D01*
G01X-514341Y294236D02*
X-515391Y292736D01*
G01X-508503Y292986D02*
X-507978Y293736D01*
G01D02*
X-507366Y294111D01*
G01D02*
X-506666Y294236D01*
G01D02*
X-505791Y293986D01*
G01X-498868Y2539D02*
Y163760D01*
G01X-502553Y76136D02*
X-506403Y70636D01*
G01X-504478Y69636D02*
Y77136D01*
G01X-506403Y76136D02*
X-502553Y70636D01*
G01X-505091Y291861D02*
X-505441Y291236D01*
G01X-505791Y293986D02*
X-505178Y293361D01*
G01D02*
X-505003Y292611D01*
G01D02*
X-505091Y291861D01*
G01X-485500Y-303000D02*
X-172980D01*
G01X-485500D02*
X-173000D01*
G01X-464232Y80705D02*
X-466482D01*
G01D02*
Y81205D01*
G01D02*
X-466370Y81365D01*
G01D02*
X-466220Y81465D01*
G01D02*
X-465920Y81505D01*
G01D02*
X-465620Y81465D01*
G01D02*
X-465432Y81345D01*
G01D02*
X-465320Y81205D01*
G01D02*
Y80705D01*
G01Y81205D02*
X-464232Y81505D01*
G01Y82455D02*
X-466482D01*
G01D02*
X-466032Y82215D01*
G01X-464232D02*
Y82694D01*
G01X-468428Y74365D02*
Y89195D01*
G01X-460675Y74365D02*
X-468428D01*
G01X-460675Y89195D02*
Y74365D01*
G01X-468428Y89195D02*
X-460675D01*
G01X-462219Y263344D02*
X-466069Y257844D01*
G01X-464144Y256844D02*
Y264344D01*
G01X-466069Y263344D02*
X-462219Y257844D01*
G01X-461519Y260594D02*
X-466769D01*
G01X-448642Y182543D02*
Y406953D01*
G01X-263007Y175882D02*
Y232574D01*
G01X-206314Y175882D02*
X-263007D01*
G01Y232574D02*
X-206314D01*
G01X-242728Y86693D02*
X-214972D01*
G01X-242728Y145748D02*
Y86693D01*
G01X-214972Y145748D02*
X-242728D01*
G01X-243551Y195779D02*
X-243114Y195029D01*
G01D02*
X-242589Y194529D01*
G01D02*
X-241976Y194280D01*
G01D02*
X-241276Y194529D01*
G01D02*
X-240751Y195029D01*
G01D02*
X-240226Y195779D01*
G01D02*
X-240051Y196779D01*
G01D02*
Y201780D01*
G01X-229782Y96579D02*
X-235282Y100429D01*
G01X-236282Y98504D02*
X-228782D01*
G01X-229782Y100429D02*
X-235282Y96579D01*
G01X-232531Y95879D02*
Y101129D01*
G01X-232179Y119186D02*
X-231829Y118061D01*
G01D02*
X-231129Y117311D01*
G01D02*
X-230254Y117061D01*
G01D02*
X-229379Y117311D01*
G01D02*
X-228679Y118061D01*
G01D02*
X-228329Y119186D01*
G01X-224679Y118561D02*
X-224154Y117686D01*
G01D02*
X-223454Y117186D01*
G01D02*
X-222666Y117061D01*
G01X-232179Y124561D02*
Y119186D01*
G01X-228329D02*
Y124561D01*
G01X-222404D02*
X-223191Y124436D01*
G01D02*
X-223979Y123936D01*
G01X-234651Y197530D02*
X-235439Y196654D01*
G01D02*
X-235964Y195404D01*
G01D02*
X-236139Y194280D01*
G01D02*
X-232464D01*
G01X-226976D02*
X-226801Y195904D01*
G01D02*
X-226539Y197279D01*
G01X-235964Y200530D02*
X-235439Y201279D01*
G01D02*
X-234826Y201655D01*
G01D02*
X-234126Y201780D01*
G01D02*
X-233251Y201530D01*
G01D02*
X-232639Y200904D01*
G01D02*
X-232464Y200155D01*
G01D02*
X-232551Y199404D01*
G01D02*
X-232901Y198779D01*
G01D02*
X-234651Y197530D01*
G01X-226539Y197279D02*
X-226189Y198530D01*
G01D02*
X-225751Y199904D01*
G01D02*
X-225051Y201780D01*
G01D02*
X-228551D01*
G01X-216009Y216630D02*
X-223509D01*
G01X-214972Y86693D02*
Y145748D01*
G01X-222666Y117061D02*
X-221966Y117186D01*
G01D02*
X-221266Y117811D01*
G01D02*
X-220829Y118561D01*
G01D02*
X-220741Y119311D01*
G01D02*
X-220916Y120186D01*
G01D02*
X-221529Y120811D01*
G01D02*
X-222141Y121061D01*
G01D02*
X-222929D01*
G01X-222141D02*
X-221616Y121436D01*
G01D02*
X-221179Y122061D01*
G01D02*
X-221004Y122811D01*
G01D02*
X-221179Y123561D01*
G01D02*
X-221616Y124186D01*
G01D02*
X-222404Y124561D01*
G01X-222509Y218555D02*
X-217009Y214705D01*
G01X-222509D02*
X-217009Y218555D01*
G01X-219759Y219255D02*
Y214005D01*
G01X-206314Y232574D02*
Y175882D01*
G01X-166270Y2539D02*
X-48750D01*
G01X-166270Y213957D02*
Y2539D01*
G01X-48750Y213957D02*
X-166270D01*
G01X-119034Y194036D02*
X-118596Y193286D01*
G01D02*
X-118072Y192786D01*
G01D02*
X-117459Y192536D01*
G01D02*
X-116759Y192786D01*
G01D02*
X-116234Y193286D01*
G01D02*
X-115709Y194036D01*
G01D02*
X-115534Y195036D01*
G01D02*
Y200036D01*
G01X-109784Y192536D02*
Y200036D01*
G01X-110834Y192536D02*
X-108734D01*
G01X-104209Y194036D02*
X-103684Y193161D01*
G01D02*
X-102984Y192661D01*
G01D02*
X-102196Y192536D01*
G01D02*
X-101496Y192661D01*
G01D02*
X-100796Y193286D01*
G01D02*
X-100359Y194036D01*
G01D02*
X-100272Y194786D01*
G01D02*
X-100446Y195661D01*
G01D02*
X-101059Y196286D01*
G01D02*
X-101672Y196536D01*
G01D02*
X-102459D01*
G01X-101672D02*
X-101146Y196911D01*
G01X-109784Y200036D02*
X-110834Y198536D01*
G01X-101146Y196911D02*
X-100709Y197536D01*
G01D02*
X-100534Y198286D01*
G01D02*
X-100709Y199036D01*
G01D02*
X-101146Y199661D01*
G01D02*
X-101934Y200036D01*
G01D02*
X-102721Y199911D01*
G01D02*
X-103509Y199411D01*
G01X-54360Y70226D02*
Y77726D01*
G01X-52435Y76726D02*
X-56285Y71226D01*
G01Y76726D02*
X-52435Y71226D01*
G01X-51735Y73976D02*
X-56985D01*
G01X-48750Y2539D02*
Y213957D01*
G01X-12475Y149665D02*
X-20228D01*
G01D02*
Y164494D01*
G01D02*
X-12475D01*
G01X-15170Y155330D02*
X-17420D01*
G01D02*
Y155830D01*
G01D02*
X-17308Y155990D01*
G01D02*
X-17158Y156090D01*
G01D02*
X-16858Y156130D01*
G01D02*
X-16558Y156090D01*
G01D02*
X-16370Y155970D01*
G01D02*
X-16258Y155830D01*
G01D02*
Y155330D01*
G01Y155830D02*
X-15170Y156130D01*
G01Y157080D02*
X-15208Y157220D01*
G01D02*
X-15320Y157380D01*
G01D02*
X-15508Y157480D01*
G01D02*
X-15770Y157520D01*
G01D02*
X-16033Y157480D01*
G01D02*
X-16258Y157360D01*
G01D02*
X-16370Y157180D01*
G01D02*
Y156980D01*
G01D02*
X-16445Y156860D01*
G01D02*
X-16633Y156760D01*
G01D02*
X-16895Y156720D01*
G01D02*
X-17158Y156780D01*
G01D02*
X-17345Y156920D01*
G01D02*
X-17420Y157080D01*
G01D02*
X-17345Y157240D01*
G01D02*
X-17158Y157380D01*
G01D02*
X-16895Y157440D01*
G01D02*
X-16633Y157400D01*
G01D02*
X-16445Y157300D01*
G01D02*
X-16370Y157180D01*
G01D02*
Y156980D01*
G01D02*
X-16258Y156800D01*
G01D02*
X-16033Y156680D01*
G01D02*
X-15770Y156640D01*
G01D02*
X-15508Y156680D01*
G01D02*
X-15320Y156780D01*
G01D02*
X-15208Y156940D01*
G01D02*
X-15170Y157080D01*
G01X-16108Y158050D02*
X-16370Y158190D01*
G01D02*
X-16520Y158310D01*
G01D02*
X-16595Y158470D01*
G01D02*
X-16520Y158610D01*
G01D02*
X-16370Y158710D01*
G01D02*
X-16145Y158790D01*
G01D02*
X-15883Y158810D01*
G01D02*
X-15658Y158790D01*
G01D02*
X-15433Y158710D01*
G01D02*
X-15245Y158590D01*
G01D02*
X-15170Y158450D01*
G01D02*
X-15245Y158290D01*
G01D02*
X-15470Y158150D01*
G01D02*
X-15808Y158070D01*
G01D02*
X-16183Y158050D01*
G01D02*
X-16670Y158090D01*
G01D02*
X-16933Y158150D01*
G01D02*
X-17195Y158250D01*
G01D02*
X-17383Y158390D01*
G01D02*
X-17420Y158530D01*
G01D02*
X-17345Y158670D01*
G01D02*
X-17158Y158770D01*
G01X-12475Y164494D02*
Y149665D01*
G01X16553Y63795D02*
X80003D01*
G01X16553Y253095D02*
Y63795D01*
G01X24828Y85270D02*
X19328Y89120D01*
G01X24828D02*
X19328Y85270D01*
G01X22078Y84570D02*
Y89820D01*
G01X18328Y87195D02*
X25828D01*
G01X80003Y253095D02*
X16553D01*
G01X38650Y157561D02*
X39088Y156811D01*
G01D02*
X39612Y156311D01*
G01D02*
X40225Y156061D01*
G01D02*
X40925Y156311D01*
G01D02*
X41450Y156811D01*
G01D02*
X41975Y157561D01*
G01D02*
X42150Y158561D01*
G01D02*
Y163561D01*
G01X47900Y156061D02*
Y163561D01*
G01D02*
X46850Y162061D01*
G01Y156061D02*
X48950D01*
G01X56450D02*
Y163561D01*
G01D02*
X53212Y158186D01*
G01D02*
X57588D01*
G01X80003Y63795D02*
Y253095D01*
G01X106860Y167303D02*
G03X126939I10039J0D01*
G01X106860D02*
Y188139D01*
G01X126939D02*
G03X106860I-10039J14597D01*
G01X126939D02*
Y167303D01*
G01X196537Y48425D02*
X211596D01*
G01X196537Y187973D02*
Y48425D01*
G01X259431Y187973D02*
X196537D01*
G01X211596Y-128149D02*
X244372D01*
G01X211596Y48425D02*
Y-128149D01*
G01X229909Y126982D02*
X226059Y121482D01*
G01X227984Y120482D02*
Y127982D01*
G01X226059Y126982D02*
X229909Y121482D01*
G01X230609Y124232D02*
X225359D01*
G01X218780Y163172D02*
X219218Y162422D01*
G01D02*
X219743Y161923D01*
G01D02*
X220355Y161673D01*
G01D02*
X221055Y161923D01*
G01D02*
X221580Y162422D01*
G01D02*
X222105Y163172D01*
G01D02*
X222280Y164173D01*
G01D02*
Y169173D01*
G01X228030Y161673D02*
Y169173D01*
G01X226980Y161673D02*
X229080D01*
G01X233605Y162797D02*
X234130Y162172D01*
G01X228030Y169173D02*
X226980Y167673D01*
G01X244372Y-128149D02*
Y48425D01*
G01D02*
X259431D01*
G01X234130Y162172D02*
X234743Y161798D01*
G01D02*
X235530Y161673D01*
G01D02*
X236318Y161923D01*
G01D02*
X236930Y162422D01*
G01D02*
X237368Y163297D01*
G01D02*
X237455Y164297D01*
G01D02*
X237280Y165297D01*
G01D02*
X236843Y165923D01*
G01D02*
X236230Y166422D01*
G01D02*
X235618Y166547D01*
G01D02*
X235005Y166422D01*
G01D02*
X234218Y165923D01*
G01D02*
X234480Y169173D01*
G01D02*
X236843D01*
G01X260315Y9331D02*
X330295D01*
G01X260315Y182362D02*
Y9331D01*
G01X259431Y48425D02*
Y187973D01*
G01X330295Y182362D02*
X260315D01*
G01X263047Y228756D02*
Y222803D01*
G01D02*
X274850D01*
G01Y228756D02*
X263047D01*
G01X261547Y233153D02*
Y240906D01*
G01X276350Y233153D02*
X261547D01*
G01Y240906D02*
X276350D01*
G01X269758Y146384D02*
X273608Y151884D01*
G01X271683Y152884D02*
Y145384D01*
G01X273608Y146384D02*
X269758Y151884D01*
G01X269058Y149134D02*
X274308D01*
G01X274780Y209753D02*
X280733D01*
G01X274780Y221555D02*
Y209753D01*
G01X280733D02*
Y221555D01*
G01X268039Y226809D02*
X267919Y226921D01*
G01D02*
X267779Y226996D01*
G01D02*
X267619D01*
G01D02*
X267439Y226884D01*
G01D02*
X267299Y226696D01*
G01D02*
X267199Y226471D01*
G01D02*
X267119Y226096D01*
G01D02*
X267099Y225759D01*
G01D02*
X267139Y225421D01*
G01D02*
X267199Y225196D01*
G01D02*
X267319Y224971D01*
G01D02*
X267459Y224821D01*
G01D02*
X267599Y224746D01*
G01D02*
X267739D01*
G01D02*
X267879Y224821D01*
G01D02*
X267999Y224934D01*
G01D02*
X268099Y225083D01*
G01X268949Y224746D02*
Y226996D01*
G01D02*
X268709Y226546D01*
G01Y224746D02*
X269189D01*
G01X269919Y225684D02*
X270059Y225946D01*
G01D02*
X270179Y226096D01*
G01D02*
X270339Y226171D01*
G01D02*
X270479Y226096D01*
G01D02*
X270579Y225946D01*
G01D02*
X270659Y225721D01*
G01D02*
X270679Y225459D01*
G01D02*
X270659Y225234D01*
G01D02*
X270579Y225008D01*
G01D02*
X270459Y224821D01*
G01D02*
X270319Y224746D01*
G01D02*
X270159Y224821D01*
G01D02*
X270019Y225046D01*
G01D02*
X269939Y225384D01*
G01D02*
X269919Y225759D01*
G01D02*
X269959Y226246D01*
G01D02*
X270019Y226509D01*
G01D02*
X270119Y226771D01*
G01D02*
X270259Y226959D01*
G01D02*
X270399Y226996D01*
G01D02*
X270539Y226921D01*
G01D02*
X270639Y226734D01*
G01X274850Y222803D02*
Y228756D01*
G01X276727Y214744D02*
X276615Y214624D01*
G01D02*
X276540Y214484D01*
G01D02*
Y214324D01*
G01D02*
X276652Y214144D01*
G01D02*
X276840Y214004D01*
G01D02*
X277065Y213904D01*
G01D02*
X277440Y213824D01*
G01D02*
X277777Y213804D01*
G01D02*
X278115Y213844D01*
G01D02*
X278340Y213904D01*
G01D02*
X278565Y214024D01*
G01D02*
X278715Y214164D01*
G01D02*
X278790Y214304D01*
G01D02*
Y214444D01*
G01D02*
X278715Y214584D01*
G01D02*
X278602Y214704D01*
G01D02*
X278452Y214804D01*
G01X278790Y215654D02*
X276540D01*
G01D02*
X276990Y215414D01*
G01X278790D02*
Y215894D01*
G01X278452Y216564D02*
X278640Y216684D01*
G01D02*
X278752Y216824D01*
G01D02*
X278790Y217004D01*
G01D02*
X278715Y217184D01*
G01D02*
X278565Y217324D01*
G01D02*
X278302Y217424D01*
G01D02*
X278002Y217444D01*
G01D02*
X277702Y217404D01*
G01D02*
X277515Y217304D01*
G01D02*
X277365Y217164D01*
G01D02*
X277327Y217024D01*
G01D02*
X277365Y216884D01*
G01D02*
X277515Y216704D01*
G01D02*
X276540Y216764D01*
G01D02*
Y217304D01*
G01X280733Y221555D02*
X274780D01*
G01X268039Y237911D02*
X267919Y238023D01*
G01D02*
X267779Y238098D01*
G01D02*
X267619D01*
G01D02*
X267439Y237986D01*
G01D02*
X267299Y237798D01*
G01D02*
X267199Y237573D01*
G01D02*
X267119Y237198D01*
G01D02*
X267099Y236861D01*
G01D02*
X267139Y236523D01*
G01D02*
X267199Y236298D01*
G01D02*
X267319Y236073D01*
G01D02*
X267459Y235923D01*
G01D02*
X267599Y235848D01*
G01D02*
X267739D01*
G01D02*
X267879Y235923D01*
G01D02*
X267999Y236036D01*
G01D02*
X268099Y236186D01*
G01X268949Y235848D02*
Y238098D01*
G01D02*
X268709Y237648D01*
G01Y235848D02*
X269189D01*
G01X270539D02*
Y238098D01*
G01D02*
X269799Y236486D01*
G01D02*
X270799D01*
G01X280672Y234265D02*
Y249094D01*
G01X288425Y234265D02*
X280672D01*
G01X276350Y240906D02*
Y233153D01*
G01X280672Y249094D02*
X288425D01*
G01X267224Y304754D02*
X282224D01*
G01X267224Y334754D02*
Y304754D01*
G01X277484Y310329D02*
X271984Y314179D01*
G01X270984Y312254D02*
X278484D01*
G01X277484Y314179D02*
X271984Y310329D01*
G01X274734Y309629D02*
Y314879D01*
G01X276149Y317680D02*
X276674Y317992D01*
G01D02*
X277024Y318367D01*
G01D02*
X277199Y318804D01*
G01D02*
X277024Y319304D01*
G01D02*
X276674Y319680D01*
G01D02*
X276149Y320055D01*
G01D02*
X275449Y320180D01*
G01D02*
X271949D01*
G01X276411Y322842D02*
X277199Y322717D01*
G01D02*
Y325342D01*
G01X282224Y334754D02*
X267224D01*
G01X272824Y322842D02*
X272299Y323217D01*
G01D02*
X272036Y323655D01*
G01D02*
X271949Y324155D01*
G01D02*
X272124Y324780D01*
G01D02*
X272561Y325217D01*
G01D02*
X273086Y325342D01*
G01D02*
X273611Y325280D01*
G01D02*
X274049Y325029D01*
G01D02*
X274924Y323780D01*
G01D02*
X275536Y323217D01*
G01D02*
X276411Y322842D01*
G01X276586Y328067D02*
X277024Y328504D01*
G01D02*
X277199Y329004D01*
G01D02*
X277024Y329504D01*
G01D02*
X276499Y329942D01*
G01D02*
X275711Y330255D01*
G01D02*
X274924Y330380D01*
G01D02*
X273961D01*
G01D02*
X273174Y330255D01*
G01D02*
X272474Y329942D01*
G01D02*
X272124Y329567D01*
G01D02*
X271949Y329129D01*
G01D02*
X272124Y328629D01*
G01D02*
X272474Y328255D01*
G01D02*
X272999Y328004D01*
G01D02*
X273699Y327880D01*
G01D02*
X274311Y328004D01*
G01D02*
X274924Y328317D01*
G01D02*
X275274Y328692D01*
G01D02*
X275361Y329129D01*
G01D02*
X275186Y329629D01*
G01D02*
X274749Y330005D01*
G01D02*
X273961Y330380D01*
G01X275075Y339865D02*
X267322D01*
G01D02*
Y354694D01*
G01X280630Y345530D02*
X278380D01*
G01D02*
Y346030D01*
G01D02*
X278492Y346190D01*
G01D02*
X278642Y346290D01*
G01D02*
X278942Y346330D01*
G01D02*
X279242Y346290D01*
G01D02*
X279430Y346170D01*
G01D02*
X279542Y346030D01*
G01D02*
Y345530D01*
G01Y346030D02*
X280630Y346330D01*
G01X280180Y346840D02*
X280442Y346960D01*
G01D02*
X280592Y347120D01*
G01D02*
X280630Y347300D01*
G01D02*
X280592Y347460D01*
G01D02*
X280405Y347620D01*
G01D02*
X280180Y347720D01*
G01D02*
X279955Y347740D01*
G01D02*
X279692Y347700D01*
G01D02*
X279505Y347560D01*
G01D02*
X279430Y347420D01*
G01D02*
Y347240D01*
G01Y347420D02*
X279317Y347540D01*
G01D02*
X279130Y347640D01*
G01D02*
X278905Y347680D01*
G01D02*
X278680Y347640D01*
G01D02*
X278492Y347540D01*
G01D02*
X278380Y347360D01*
G01D02*
X278417Y347180D01*
G01D02*
X278567Y347000D01*
G01X280630Y348630D02*
X280592Y348770D01*
G01D02*
X280480Y348930D01*
G01D02*
X280292Y349030D01*
G01D02*
X280030Y349070D01*
G01D02*
X279767Y349030D01*
G01D02*
X279542Y348910D01*
G01D02*
X279430Y348730D01*
G01D02*
Y348530D01*
G01D02*
X279355Y348410D01*
G01D02*
X279167Y348310D01*
G01D02*
X278905Y348270D01*
G01D02*
X278642Y348330D01*
G01D02*
X278455Y348470D01*
G01D02*
X278380Y348630D01*
G01D02*
X278455Y348790D01*
G01D02*
X278642Y348930D01*
G01D02*
X278905Y348990D01*
G01D02*
X279167Y348950D01*
G01D02*
X279355Y348850D01*
G01D02*
X279430Y348730D01*
G01D02*
Y348530D01*
G01D02*
X279542Y348350D01*
G01D02*
X279767Y348230D01*
G01D02*
X280030Y348190D01*
G01D02*
X280292Y348230D01*
G01D02*
X280480Y348330D01*
G01D02*
X280592Y348490D01*
G01D02*
X280630Y348630D01*
G01X283325Y339865D02*
X275572D01*
G01D02*
Y354694D01*
G01X272380Y345530D02*
X270130D01*
G01D02*
Y346030D01*
G01D02*
X270242Y346190D01*
G01D02*
X270392Y346290D01*
G01D02*
X270692Y346330D01*
G01D02*
X270992Y346290D01*
G01D02*
X271180Y346170D01*
G01D02*
X271292Y346030D01*
G01D02*
Y345530D01*
G01Y346030D02*
X272380Y346330D01*
G01X271930Y346840D02*
X272192Y346960D01*
G01D02*
X272342Y347120D01*
G01D02*
X272380Y347300D01*
G01D02*
X272342Y347460D01*
G01D02*
X272155Y347620D01*
G01D02*
X271930Y347720D01*
G01D02*
X271705Y347740D01*
G01D02*
X271442Y347700D01*
G01D02*
X271255Y347560D01*
G01D02*
X271180Y347420D01*
G01D02*
Y347240D01*
G01Y347420D02*
X271067Y347540D01*
G01D02*
X270880Y347640D01*
G01D02*
X270655Y347680D01*
G01D02*
X270430Y347640D01*
G01D02*
X270242Y347540D01*
G01D02*
X270130Y347360D01*
G01D02*
X270167Y347180D01*
G01D02*
X270317Y347000D01*
G01X272117Y348290D02*
X272305Y348430D01*
G01D02*
X272380Y348590D01*
G01D02*
X272305Y348750D01*
G01D02*
X272080Y348890D01*
G01D02*
X271742Y348990D01*
G01D02*
X271405Y349030D01*
G01D02*
X270992D01*
G01D02*
X270655Y348990D01*
G01D02*
X270355Y348890D01*
G01D02*
X270205Y348770D01*
G01D02*
X270130Y348630D01*
G01D02*
X270205Y348470D01*
G01D02*
X270355Y348350D01*
G01D02*
X270580Y348270D01*
G01D02*
X270880Y348230D01*
G01D02*
X271142Y348270D01*
G01D02*
X271405Y348370D01*
G01D02*
X271555Y348490D01*
G01D02*
X271592Y348630D01*
G01D02*
X271517Y348790D01*
G01D02*
X271330Y348910D01*
G01D02*
X270992Y349030D01*
G01X275075Y354694D02*
Y339865D01*
G01X267322Y354694D02*
X275075D01*
G01X275572D02*
X283325D01*
G01X286055Y162898D02*
X286492Y162147D01*
G01D02*
X287017Y161648D01*
G01D02*
X287630Y161398D01*
G01D02*
X288330Y161648D01*
G01D02*
X288855Y162147D01*
G01D02*
X289380Y162898D01*
G01D02*
X289555Y163898D01*
G01D02*
Y168898D01*
G01X295305Y161398D02*
Y168898D01*
G01X294255Y161398D02*
X296355D01*
G01X295305Y168898D02*
X294255Y167398D01*
G01X289883Y209003D02*
X282130D01*
G01X289883Y223805D02*
Y209003D01*
G01X282130D02*
Y223805D01*
G01X285125Y215494D02*
X285012Y215374D01*
G01D02*
X284937Y215234D01*
G01D02*
Y215074D01*
G01D02*
X285050Y214894D01*
G01D02*
X285237Y214754D01*
G01D02*
X285462Y214654D01*
G01D02*
X285837Y214574D01*
G01D02*
X286175Y214554D01*
G01D02*
X286512Y214594D01*
G01D02*
X286737Y214654D01*
G01D02*
X286962Y214774D01*
G01D02*
X287112Y214914D01*
G01D02*
X287187Y215054D01*
G01D02*
Y215194D01*
G01D02*
X287112Y215334D01*
G01D02*
X287000Y215454D01*
G01D02*
X286850Y215554D01*
G01X287187Y216404D02*
X284937D01*
G01D02*
X285387Y216164D01*
G01X287187D02*
Y216644D01*
G01X286737Y217314D02*
X287000Y217434D01*
G01D02*
X287150Y217594D01*
G01D02*
X287187Y217774D01*
G01D02*
X287150Y217934D01*
G01D02*
X286962Y218094D01*
G01D02*
X286737Y218194D01*
G01D02*
X286512Y218214D01*
G01D02*
X286250Y218174D01*
G01D02*
X286062Y218034D01*
G01D02*
X285987Y217894D01*
G01D02*
Y217714D01*
G01Y217894D02*
X285875Y218014D01*
G01D02*
X285687Y218114D01*
G01D02*
X285462Y218154D01*
G01D02*
X285237Y218114D01*
G01D02*
X285050Y218014D01*
G01D02*
X284937Y217834D01*
G01D02*
X284975Y217654D01*
G01D02*
X285125Y217474D01*
G01X282130Y223805D02*
X289883D01*
G01X296184Y226253D02*
Y234006D01*
G01X311014Y226253D02*
X296184D01*
G01Y225756D02*
X311014D01*
G01X296184Y218003D02*
Y225756D01*
G01X311014Y218003D02*
X296184D01*
G01X288425Y249094D02*
Y234265D01*
G01X285449Y239780D02*
X283199D01*
G01D02*
Y240280D01*
G01D02*
X283311Y240440D01*
G01D02*
X283461Y240540D01*
G01D02*
X283761Y240580D01*
G01D02*
X284061Y240540D01*
G01D02*
X284249Y240420D01*
G01D02*
X284361Y240280D01*
G01D02*
Y239780D01*
G01Y240280D02*
X285449Y240580D01*
G01Y241490D02*
X284961Y241530D01*
G01D02*
X284549Y241590D01*
G01D02*
X284174Y241670D01*
G01D02*
X283761Y241770D01*
G01D02*
X283199Y241930D01*
G01D02*
Y241130D01*
G01Y242880D02*
X283274Y242720D01*
G01D02*
X283461Y242600D01*
G01D02*
X283686Y242520D01*
G01D02*
X283986Y242460D01*
G01D02*
X284324Y242440D01*
G01D02*
X284661Y242460D01*
G01D02*
X284961Y242520D01*
G01D02*
X285186Y242600D01*
G01D02*
X285374Y242720D01*
G01D02*
X285449Y242880D01*
G01D02*
X285374Y243040D01*
G01D02*
X285186Y243160D01*
G01D02*
X284961Y243240D01*
G01D02*
X284661Y243300D01*
G01D02*
X284324Y243320D01*
G01D02*
X283986Y243300D01*
G01D02*
X283686Y243240D01*
G01D02*
X283461Y243160D01*
G01D02*
X283274Y243040D01*
G01D02*
X283199Y242880D01*
G01X296184Y234503D02*
Y242256D01*
G01X311014Y234503D02*
X296184D01*
G01Y234006D02*
X311014D01*
G01X296184Y242256D02*
X311014D01*
G01X296184Y242753D02*
Y250506D01*
G01X311014Y242753D02*
X296184D01*
G01Y250506D02*
X311014D01*
G01X296184Y251003D02*
Y258756D01*
G01X311014Y251003D02*
X296184D01*
G01Y259253D02*
Y267006D01*
G01X311014Y259253D02*
X296184D01*
G01Y258756D02*
X311014D01*
G01X296184Y267503D02*
Y275256D01*
G01X311014Y267503D02*
X296184D01*
G01Y275256D02*
X311014D01*
G01X296184Y267006D02*
X311014D01*
G01X296184Y275753D02*
Y283506D01*
G01X311014Y275753D02*
X296184D01*
G01Y284003D02*
Y291756D01*
G01X311014Y284003D02*
X296184D01*
G01Y283506D02*
X311014D01*
G01X282224Y304754D02*
Y334754D01*
G01X292724Y304754D02*
X307724D01*
G01X292724Y334754D02*
Y304754D01*
G01X296184Y300006D02*
X311014D01*
G01X296184Y292253D02*
Y300006D01*
G01X311014Y292253D02*
X296184D01*
G01Y291756D02*
X311014D01*
G01X296484Y312254D02*
X303984D01*
G01X307724Y334754D02*
X292724D01*
G01X283325Y354694D02*
Y339865D01*
G01X302075D02*
X294322D01*
G01D02*
Y354694D01*
G01D02*
X302075D01*
G01X301142Y164522D02*
X301755Y165398D01*
G01X304030D02*
X304380Y164648D01*
G01D02*
X304467Y163773D01*
G01D02*
X304380Y163023D01*
G01D02*
X304030Y162272D01*
G01D02*
X303505Y161648D01*
G01D02*
X302892Y161398D01*
G01D02*
X302192Y161648D01*
G01D02*
X301580Y162397D01*
G01D02*
X301230Y163523D01*
G01D02*
X301142Y164773D01*
G01D02*
X301317Y166397D01*
G01X301755Y165398D02*
X302280Y165898D01*
G01D02*
X302980Y166148D01*
G01D02*
X303592Y165898D01*
G01D02*
X304030Y165398D01*
G01X301317Y166397D02*
X301580Y167273D01*
G01D02*
X302017Y168148D01*
G01D02*
X302630Y168773D01*
G01D02*
X303242Y168898D01*
G01D02*
X303855Y168648D01*
G01D02*
X304292Y168023D01*
G01X311014Y234006D02*
Y226253D01*
G01X301849Y221561D02*
Y223811D01*
G01D02*
X302349D01*
G01D02*
X302509Y223698D01*
G01D02*
X302609Y223548D01*
G01D02*
X302649Y223248D01*
G01D02*
X302609Y222948D01*
G01D02*
X302489Y222761D01*
G01D02*
X302349Y222648D01*
G01D02*
X301849D01*
G01X302349D02*
X302649Y221561D01*
G01X303159Y222011D02*
X303279Y221748D01*
G01D02*
X303439Y221598D01*
G01D02*
X303619Y221561D01*
G01D02*
X303779Y221598D01*
G01D02*
X303939Y221786D01*
G01D02*
X304039Y222011D01*
G01D02*
X304059Y222236D01*
G01D02*
X304019Y222498D01*
G01D02*
X303879Y222686D01*
G01D02*
X303739Y222761D01*
G01D02*
X303559D01*
G01X303739D02*
X303859Y222873D01*
G01D02*
X303959Y223061D01*
G01D02*
X303999Y223286D01*
G01D02*
X303959Y223511D01*
G01D02*
X303859Y223698D01*
G01D02*
X303679Y223811D01*
G01D02*
X303499Y223773D01*
G01D02*
X303319Y223623D01*
G01X304509Y221898D02*
X304629Y221711D01*
G01D02*
X304769Y221598D01*
G01D02*
X304949Y221561D01*
G01D02*
X305129Y221636D01*
G01D02*
X305269Y221786D01*
G01D02*
X305369Y222048D01*
G01D02*
X305389Y222348D01*
G01D02*
X305349Y222648D01*
G01D02*
X305249Y222836D01*
G01D02*
X305109Y222986D01*
G01D02*
X304969Y223023D01*
G01D02*
X304829Y222986D01*
G01D02*
X304649Y222836D01*
G01D02*
X304709Y223811D01*
G01D02*
X305249D01*
G01X311014Y225756D02*
Y218003D01*
G01Y242256D02*
Y234503D01*
G01X301849Y228948D02*
Y231198D01*
G01D02*
X302349D01*
G01D02*
X302509Y231086D01*
G01D02*
X302609Y230936D01*
G01D02*
X302649Y230636D01*
G01D02*
X302609Y230336D01*
G01D02*
X302489Y230148D01*
G01D02*
X302349Y230036D01*
G01D02*
X301849D01*
G01X302349D02*
X302649Y228948D01*
G01X303159Y229398D02*
X303279Y229136D01*
G01D02*
X303439Y228986D01*
G01D02*
X303619Y228948D01*
G01D02*
X303779Y228986D01*
G01D02*
X303939Y229173D01*
G01D02*
X304039Y229398D01*
G01D02*
X304059Y229623D01*
G01D02*
X304019Y229886D01*
G01D02*
X303879Y230073D01*
G01D02*
X303739Y230148D01*
G01D02*
X303559D01*
G01X303739D02*
X303859Y230261D01*
G01D02*
X303959Y230448D01*
G01D02*
X303999Y230673D01*
G01D02*
X303959Y230898D01*
G01D02*
X303859Y231086D01*
G01D02*
X303679Y231198D01*
G01D02*
X303499Y231161D01*
G01D02*
X303319Y231011D01*
G01X305189Y228948D02*
Y231198D01*
G01D02*
X304449Y229586D01*
G01D02*
X305449D01*
G01X301849Y238061D02*
Y240311D01*
G01D02*
X302349D01*
G01D02*
X302509Y240198D01*
G01D02*
X302609Y240048D01*
G01D02*
X302649Y239748D01*
G01D02*
X302609Y239448D01*
G01D02*
X302489Y239261D01*
G01D02*
X302349Y239148D01*
G01D02*
X301849D01*
G01X302349D02*
X302649Y238061D01*
G01X303219Y238998D02*
X303359Y239261D01*
G01D02*
X303479Y239411D01*
G01D02*
X303639Y239486D01*
G01D02*
X303779Y239411D01*
G01D02*
X303879Y239261D01*
G01D02*
X303959Y239036D01*
G01D02*
X303979Y238773D01*
G01D02*
X303959Y238548D01*
G01D02*
X303879Y238323D01*
G01D02*
X303759Y238136D01*
G01D02*
X303619Y238061D01*
G01D02*
X303459Y238136D01*
G01D02*
X303319Y238361D01*
G01D02*
X303239Y238698D01*
G01D02*
X303219Y239073D01*
G01D02*
X303259Y239561D01*
G01D02*
X303319Y239823D01*
G01D02*
X303419Y240086D01*
G01D02*
X303559Y240273D01*
G01D02*
X303699Y240311D01*
G01D02*
X303839Y240236D01*
G01D02*
X303939Y240048D01*
G01X304949Y238061D02*
Y240311D01*
G01D02*
X304709Y239861D01*
G01Y238061D02*
X305189D01*
G01X311014Y250506D02*
Y242753D01*
G01X301849Y245448D02*
Y247698D01*
G01D02*
X302349D01*
G01D02*
X302509Y247586D01*
G01D02*
X302609Y247436D01*
G01D02*
X302649Y247136D01*
G01D02*
X302609Y246836D01*
G01D02*
X302489Y246648D01*
G01D02*
X302349Y246536D01*
G01D02*
X301849D01*
G01X302349D02*
X302649Y245448D01*
G01X303219Y246386D02*
X303359Y246648D01*
G01D02*
X303479Y246798D01*
G01D02*
X303639Y246873D01*
G01D02*
X303779Y246798D01*
G01D02*
X303879Y246648D01*
G01D02*
X303959Y246423D01*
G01D02*
X303979Y246161D01*
G01D02*
X303959Y245936D01*
G01D02*
X303879Y245711D01*
G01D02*
X303759Y245523D01*
G01D02*
X303619Y245448D01*
G01D02*
X303459Y245523D01*
G01D02*
X303319Y245748D01*
G01D02*
X303239Y246086D01*
G01D02*
X303219Y246461D01*
G01D02*
X303259Y246948D01*
G01D02*
X303319Y247211D01*
G01D02*
X303419Y247473D01*
G01D02*
X303559Y247661D01*
G01D02*
X303699Y247698D01*
G01D02*
X303839Y247623D01*
G01D02*
X303939Y247436D01*
G01X304909Y245448D02*
X304949Y245936D01*
G01D02*
X305009Y246348D01*
G01D02*
X305089Y246723D01*
G01D02*
X305189Y247136D01*
G01D02*
X305349Y247698D01*
G01D02*
X304549D01*
G01X301849Y253698D02*
Y255948D01*
G01D02*
X302349D01*
G01D02*
X302509Y255836D01*
G01D02*
X302609Y255686D01*
G01D02*
X302649Y255386D01*
G01D02*
X302609Y255086D01*
G01D02*
X302489Y254898D01*
G01D02*
X302349Y254786D01*
G01D02*
X301849D01*
G01X302349D02*
X302649Y253698D01*
G01X303219Y254636D02*
X303359Y254898D01*
G01D02*
X303479Y255048D01*
G01D02*
X303639Y255123D01*
G01D02*
X303779Y255048D01*
G01D02*
X303879Y254898D01*
G01D02*
X303959Y254673D01*
G01D02*
X303979Y254411D01*
G01D02*
X303959Y254186D01*
G01D02*
X303879Y253961D01*
G01D02*
X303759Y253773D01*
G01D02*
X303619Y253698D01*
G01D02*
X303459Y253773D01*
G01D02*
X303319Y253998D01*
G01D02*
X303239Y254336D01*
G01D02*
X303219Y254711D01*
G01D02*
X303259Y255198D01*
G01D02*
X303319Y255461D01*
G01D02*
X303419Y255723D01*
G01D02*
X303559Y255911D01*
G01D02*
X303699Y255948D01*
G01D02*
X303839Y255873D01*
G01D02*
X303939Y255686D01*
G01X304949Y253698D02*
X305089Y253736D01*
G01D02*
X305249Y253848D01*
G01D02*
X305349Y254036D01*
G01D02*
X305389Y254298D01*
G01D02*
X305349Y254561D01*
G01D02*
X305229Y254786D01*
G01D02*
X305049Y254898D01*
G01D02*
X304849D01*
G01D02*
X304729Y254973D01*
G01D02*
X304629Y255161D01*
G01D02*
X304589Y255423D01*
G01D02*
X304649Y255686D01*
G01D02*
X304789Y255873D01*
G01D02*
X304949Y255948D01*
G01D02*
X305109Y255873D01*
G01D02*
X305249Y255686D01*
G01D02*
X305309Y255423D01*
G01D02*
X305269Y255161D01*
G01D02*
X305169Y254973D01*
G01D02*
X305049Y254898D01*
G01D02*
X304849D01*
G01D02*
X304669Y254786D01*
G01D02*
X304549Y254561D01*
G01D02*
X304509Y254298D01*
G01D02*
X304549Y254036D01*
G01D02*
X304649Y253848D01*
G01D02*
X304809Y253736D01*
G01D02*
X304949Y253698D01*
G01X311014Y258756D02*
Y251003D01*
G01Y267006D02*
Y259253D01*
G01X301699Y270030D02*
Y272280D01*
G01D02*
X302199D01*
G01D02*
X302359Y272167D01*
G01D02*
X302459Y272017D01*
G01D02*
X302499Y271717D01*
G01D02*
X302459Y271417D01*
G01D02*
X302339Y271230D01*
G01D02*
X302199Y271117D01*
G01D02*
X301699D01*
G01X302199D02*
X302499Y270030D01*
G01X303069Y270967D02*
X303209Y271230D01*
G01D02*
X303329Y271380D01*
G01D02*
X303489Y271454D01*
G01D02*
X303629Y271380D01*
G01D02*
X303729Y271230D01*
G01D02*
X303809Y271005D01*
G01D02*
X303829Y270742D01*
G01D02*
X303809Y270517D01*
G01D02*
X303729Y270292D01*
G01D02*
X303609Y270105D01*
G01D02*
X303469Y270030D01*
G01D02*
X303309Y270105D01*
G01D02*
X303169Y270329D01*
G01D02*
X303089Y270667D01*
G01D02*
X303069Y271042D01*
G01D02*
X303109Y271529D01*
G01D02*
X303169Y271792D01*
G01D02*
X303269Y272055D01*
G01D02*
X303409Y272242D01*
G01D02*
X303549Y272280D01*
G01D02*
X303689Y272205D01*
G01D02*
X303789Y272017D01*
G01X304359Y270367D02*
X304479Y270180D01*
G01D02*
X304619Y270067D01*
G01D02*
X304799Y270030D01*
G01D02*
X304979Y270105D01*
G01D02*
X305119Y270254D01*
G01D02*
X305219Y270517D01*
G01D02*
X305239Y270817D01*
G01D02*
X305199Y271117D01*
G01D02*
X305099Y271305D01*
G01D02*
X304959Y271454D01*
G01D02*
X304819Y271492D01*
G01D02*
X304679Y271454D01*
G01D02*
X304499Y271305D01*
G01D02*
X304559Y272280D01*
G01D02*
X305099D01*
G01X311014Y275256D02*
Y267503D01*
G01X301849Y261948D02*
Y264198D01*
G01D02*
X302349D01*
G01D02*
X302509Y264086D01*
G01D02*
X302609Y263936D01*
G01D02*
X302649Y263636D01*
G01D02*
X302609Y263336D01*
G01D02*
X302489Y263148D01*
G01D02*
X302349Y263036D01*
G01D02*
X301849D01*
G01X302349D02*
X302649Y261948D01*
G01X303219Y262886D02*
X303359Y263148D01*
G01D02*
X303479Y263298D01*
G01D02*
X303639Y263373D01*
G01D02*
X303779Y263298D01*
G01D02*
X303879Y263148D01*
G01D02*
X303959Y262923D01*
G01D02*
X303979Y262661D01*
G01D02*
X303959Y262436D01*
G01D02*
X303879Y262211D01*
G01D02*
X303759Y262023D01*
G01D02*
X303619Y261948D01*
G01D02*
X303459Y262023D01*
G01D02*
X303319Y262248D01*
G01D02*
X303239Y262586D01*
G01D02*
X303219Y262961D01*
G01D02*
X303259Y263448D01*
G01D02*
X303319Y263711D01*
G01D02*
X303419Y263973D01*
G01D02*
X303559Y264161D01*
G01D02*
X303699Y264198D01*
G01D02*
X303839Y264123D01*
G01D02*
X303939Y263936D01*
G01X305189Y261948D02*
Y264198D01*
G01D02*
X304449Y262586D01*
G01D02*
X305449D01*
G01X301849Y278448D02*
Y280698D01*
G01D02*
X302349D01*
G01D02*
X302509Y280586D01*
G01D02*
X302609Y280436D01*
G01D02*
X302649Y280136D01*
G01D02*
X302609Y279836D01*
G01D02*
X302489Y279648D01*
G01D02*
X302349Y279536D01*
G01D02*
X301849D01*
G01X302349D02*
X302649Y278448D01*
G01X303219Y279386D02*
X303359Y279648D01*
G01D02*
X303479Y279798D01*
G01D02*
X303639Y279873D01*
G01D02*
X303779Y279798D01*
G01D02*
X303879Y279648D01*
G01D02*
X303959Y279423D01*
G01D02*
X303979Y279161D01*
G01D02*
X303959Y278936D01*
G01D02*
X303879Y278711D01*
G01D02*
X303759Y278523D01*
G01D02*
X303619Y278448D01*
G01D02*
X303459Y278523D01*
G01D02*
X303319Y278748D01*
G01D02*
X303239Y279086D01*
G01D02*
X303219Y279461D01*
G01D02*
X303259Y279948D01*
G01D02*
X303319Y280211D01*
G01D02*
X303419Y280473D01*
G01D02*
X303559Y280661D01*
G01D02*
X303699Y280698D01*
G01D02*
X303839Y280623D01*
G01D02*
X303939Y280436D01*
G01X304609Y278711D02*
X304749Y278523D01*
G01D02*
X304909Y278448D01*
G01D02*
X305069Y278523D01*
G01D02*
X305209Y278748D01*
G01D02*
X305309Y279086D01*
G01D02*
X305349Y279423D01*
G01D02*
Y279836D01*
G01D02*
X305309Y280173D01*
G01D02*
X305209Y280473D01*
G01D02*
X305089Y280623D01*
G01D02*
X304949Y280698D01*
G01D02*
X304789Y280623D01*
G01D02*
X304669Y280473D01*
G01D02*
X304589Y280248D01*
G01D02*
X304549Y279948D01*
G01D02*
X304589Y279686D01*
G01D02*
X304689Y279423D01*
G01D02*
X304809Y279273D01*
G01D02*
X304949Y279236D01*
G01D02*
X305109Y279311D01*
G01D02*
X305229Y279498D01*
G01D02*
X305349Y279836D01*
G01X311014Y283506D02*
Y275753D01*
G01X301849Y286698D02*
Y288948D01*
G01D02*
X302349D01*
G01D02*
X302509Y288836D01*
G01D02*
X302609Y288686D01*
G01D02*
X302649Y288386D01*
G01D02*
X302609Y288086D01*
G01D02*
X302489Y287898D01*
G01D02*
X302349Y287786D01*
G01D02*
X301849D01*
G01X302349D02*
X302649Y286698D01*
G01X303219Y287636D02*
X303359Y287898D01*
G01D02*
X303479Y288048D01*
G01D02*
X303639Y288123D01*
G01D02*
X303779Y288048D01*
G01D02*
X303879Y287898D01*
G01D02*
X303959Y287673D01*
G01D02*
X303979Y287411D01*
G01D02*
X303959Y287186D01*
G01D02*
X303879Y286961D01*
G01D02*
X303759Y286773D01*
G01D02*
X303619Y286698D01*
G01D02*
X303459Y286773D01*
G01D02*
X303319Y286998D01*
G01D02*
X303239Y287336D01*
G01D02*
X303219Y287711D01*
G01D02*
X303259Y288198D01*
G01D02*
X303319Y288461D01*
G01D02*
X303419Y288723D01*
G01D02*
X303559Y288911D01*
G01D02*
X303699Y288948D01*
G01D02*
X303839Y288873D01*
G01D02*
X303939Y288686D01*
G01X304569Y288573D02*
X304689Y288798D01*
G01D02*
X304829Y288911D01*
G01D02*
X304989Y288948D01*
G01D02*
X305189Y288873D01*
G01D02*
X305329Y288686D01*
G01D02*
X305369Y288461D01*
G01D02*
X305349Y288236D01*
G01D02*
X305269Y288048D01*
G01D02*
X304869Y287673D01*
G01D02*
X304689Y287411D01*
G01D02*
X304569Y287036D01*
G01D02*
X304529Y286698D01*
G01D02*
X305369D01*
G01X311014Y291756D02*
Y284003D01*
G01X307724Y304754D02*
Y334754D01*
G01X301849Y295811D02*
Y298061D01*
G01D02*
X302349D01*
G01D02*
X302509Y297948D01*
G01D02*
X302609Y297798D01*
G01D02*
X302649Y297498D01*
G01D02*
X302609Y297198D01*
G01D02*
X302489Y297011D01*
G01D02*
X302349Y296898D01*
G01D02*
X301849D01*
G01X302349D02*
X302649Y295811D01*
G01X303219Y296748D02*
X303359Y297011D01*
G01D02*
X303479Y297161D01*
G01D02*
X303639Y297236D01*
G01D02*
X303779Y297161D01*
G01D02*
X303879Y297011D01*
G01D02*
X303959Y296786D01*
G01D02*
X303979Y296523D01*
G01D02*
X303959Y296298D01*
G01D02*
X303879Y296073D01*
G01D02*
X303759Y295886D01*
G01D02*
X303619Y295811D01*
G01D02*
X303459Y295886D01*
G01D02*
X303319Y296111D01*
G01D02*
X303239Y296448D01*
G01D02*
X303219Y296823D01*
G01D02*
X303259Y297311D01*
G01D02*
X303319Y297573D01*
G01D02*
X303419Y297836D01*
G01D02*
X303559Y298023D01*
G01D02*
X303699Y298061D01*
G01D02*
X303839Y297986D01*
G01D02*
X303939Y297798D01*
G01X304509Y296261D02*
X304629Y295998D01*
G01D02*
X304789Y295848D01*
G01D02*
X304969Y295811D01*
G01D02*
X305129Y295848D01*
G01D02*
X305289Y296036D01*
G01D02*
X305389Y296261D01*
G01D02*
X305409Y296486D01*
G01D02*
X305369Y296748D01*
G01D02*
X305229Y296936D01*
G01D02*
X305089Y297011D01*
G01D02*
X304909D01*
G01X305089D02*
X305209Y297123D01*
G01D02*
X305309Y297311D01*
G01D02*
X305349Y297536D01*
G01D02*
X305309Y297761D01*
G01D02*
X305209Y297948D01*
G01D02*
X305029Y298061D01*
G01D02*
X304849Y298023D01*
G01D02*
X304669Y297873D01*
G01X311014Y300006D02*
Y292253D01*
G01X302984Y310329D02*
X297484Y314179D01*
G01X302984D02*
X297484Y310329D01*
G01X300234Y309629D02*
Y314879D01*
G01X301649Y317680D02*
X302174Y317992D01*
G01D02*
X302524Y318367D01*
G01D02*
X302699Y318804D01*
G01D02*
X302524Y319304D01*
G01D02*
X302174Y319680D01*
G01D02*
X301649Y320055D01*
G01D02*
X300949Y320180D01*
G01D02*
X297449D01*
G01X301911Y322842D02*
X302699Y322717D01*
G01D02*
Y325342D01*
G01X298324Y322842D02*
X297799Y323217D01*
G01D02*
X297536Y323655D01*
G01D02*
X297449Y324155D01*
G01D02*
X297624Y324780D01*
G01D02*
X298061Y325217D01*
G01D02*
X298586Y325342D01*
G01D02*
X299111Y325280D01*
G01D02*
X299549Y325029D01*
G01D02*
X300424Y323780D01*
G01D02*
X301036Y323217D01*
G01D02*
X301911Y322842D01*
G01X302699Y329129D02*
X302611Y329567D01*
G01D02*
X302349Y330067D01*
G01D02*
X301911Y330380D01*
G01D02*
X301299Y330505D01*
G01D02*
X300686Y330380D01*
G01D02*
X300161Y330005D01*
G01D02*
X299899Y329442D01*
G01D02*
Y328817D01*
G01D02*
X299724Y328442D01*
G01D02*
X299286Y328129D01*
G01D02*
X298674Y328004D01*
G01D02*
X298061Y328192D01*
G01D02*
X297624Y328629D01*
G01D02*
X297449Y329129D01*
G01D02*
X297624Y329629D01*
G01D02*
X298061Y330067D01*
G01D02*
X298674Y330255D01*
G01D02*
X299286Y330129D01*
G01D02*
X299724Y329817D01*
G01D02*
X299899Y329442D01*
G01D02*
Y328817D01*
G01D02*
X300161Y328255D01*
G01D02*
X300686Y327880D01*
G01D02*
X301299Y327755D01*
G01D02*
X301911Y327880D01*
G01D02*
X302349Y328192D01*
G01D02*
X302611Y328692D01*
G01D02*
X302699Y329129D01*
G01X307630Y345530D02*
X305380D01*
G01D02*
Y346030D01*
G01D02*
X305492Y346190D01*
G01D02*
X305642Y346290D01*
G01D02*
X305942Y346330D01*
G01D02*
X306242Y346290D01*
G01D02*
X306430Y346170D01*
G01D02*
X306542Y346030D01*
G01D02*
Y345530D01*
G01Y346030D02*
X307630Y346330D01*
G01X307180Y346840D02*
X307442Y346960D01*
G01D02*
X307592Y347120D01*
G01D02*
X307630Y347300D01*
G01D02*
X307592Y347460D01*
G01D02*
X307405Y347620D01*
G01D02*
X307180Y347720D01*
G01D02*
X306955Y347740D01*
G01D02*
X306692Y347700D01*
G01D02*
X306505Y347560D01*
G01D02*
X306430Y347420D01*
G01D02*
Y347240D01*
G01Y347420D02*
X306317Y347540D01*
G01D02*
X306130Y347640D01*
G01D02*
X305905Y347680D01*
G01D02*
X305680Y347640D01*
G01D02*
X305492Y347540D01*
G01D02*
X305380Y347360D01*
G01D02*
X305417Y347180D01*
G01D02*
X305567Y347000D01*
G01X306692Y348250D02*
X306430Y348390D01*
G01D02*
X306280Y348510D01*
G01D02*
X306205Y348670D01*
G01D02*
X306280Y348810D01*
G01D02*
X306430Y348910D01*
G01D02*
X306655Y348990D01*
G01D02*
X306917Y349010D01*
G01D02*
X307142Y348990D01*
G01D02*
X307367Y348910D01*
G01D02*
X307555Y348790D01*
G01D02*
X307630Y348650D01*
G01D02*
X307555Y348490D01*
G01D02*
X307330Y348350D01*
G01D02*
X306992Y348270D01*
G01D02*
X306617Y348250D01*
G01D02*
X306130Y348290D01*
G01D02*
X305867Y348350D01*
G01D02*
X305605Y348450D01*
G01D02*
X305417Y348590D01*
G01D02*
X305380Y348730D01*
G01D02*
X305455Y348870D01*
G01D02*
X305642Y348970D01*
G01X310325Y339865D02*
X302572D01*
G01X310325Y354694D02*
Y339865D01*
G01X302572D02*
Y354694D01*
G01X299380Y345530D02*
X297130D01*
G01D02*
Y346030D01*
G01D02*
X297242Y346190D01*
G01D02*
X297392Y346290D01*
G01D02*
X297692Y346330D01*
G01D02*
X297992Y346290D01*
G01D02*
X298180Y346170D01*
G01D02*
X298292Y346030D01*
G01D02*
Y345530D01*
G01Y346030D02*
X299380Y346330D01*
G01X298930Y346840D02*
X299192Y346960D01*
G01D02*
X299342Y347120D01*
G01D02*
X299380Y347300D01*
G01D02*
X299342Y347460D01*
G01D02*
X299155Y347620D01*
G01D02*
X298930Y347720D01*
G01D02*
X298705Y347740D01*
G01D02*
X298442Y347700D01*
G01D02*
X298255Y347560D01*
G01D02*
X298180Y347420D01*
G01D02*
Y347240D01*
G01Y347420D02*
X298067Y347540D01*
G01D02*
X297880Y347640D01*
G01D02*
X297655Y347680D01*
G01D02*
X297430Y347640D01*
G01D02*
X297242Y347540D01*
G01D02*
X297130Y347360D01*
G01D02*
X297167Y347180D01*
G01D02*
X297317Y347000D01*
G01X299380Y348590D02*
X298892Y348630D01*
G01D02*
X298480Y348690D01*
G01D02*
X298105Y348770D01*
G01D02*
X297692Y348870D01*
G01D02*
X297130Y349030D01*
G01D02*
Y348230D01*
G01X302075Y354694D02*
Y339865D01*
G01X302572Y354694D02*
X310325D01*
G01X330295Y9331D02*
Y182362D01*
G01X337382Y64429D02*
Y411201D01*
G01X454016Y64429D02*
X337382D01*
G01X345059Y58051D02*
G03X342106Y61004I-2953J0D01*
G01X341959Y144862D02*
Y76949D01*
G01D02*
X449439D01*
G01Y144862D02*
X341959D01*
G01X337382Y411201D02*
X454016D01*
G01X348012Y46004D02*
X449291D01*
G01X345059Y48957D02*
G03X348012Y46004I2953J0D01*
G01X345059Y58051D02*
Y48957D01*
G01X510000Y-775000D02*
X390000D01*
G01X510000Y-747500D02*
X390000D01*
G01X507500Y-715000D02*
X387500D01*
G01X510000Y-685000D02*
X390000D01*
G01X580000Y-625000D02*
X390000D01*
G01X386449Y109905D02*
X386886Y109155D01*
G01D02*
X387411Y108655D01*
G01D02*
X388024Y108405D01*
G01D02*
X388724Y108655D01*
G01D02*
X389249Y109155D01*
G01D02*
X389774Y109905D01*
G01D02*
X389949Y110905D01*
G01D02*
Y115905D01*
G01X386449Y160555D02*
X386886Y159805D01*
G01D02*
X387411Y159305D01*
G01D02*
X388024Y159055D01*
G01D02*
X388724Y159305D01*
G01D02*
X389249Y159805D01*
G01D02*
X389774Y160555D01*
G01D02*
X389949Y161555D01*
G01D02*
Y166555D01*
G01X394036Y114655D02*
X394561Y115405D01*
G01D02*
X395174Y115780D01*
G01D02*
X395874Y115905D01*
G01D02*
X396749Y115655D01*
G01D02*
X397361Y115030D01*
G01D02*
X397536Y114280D01*
G01D02*
X397449Y113530D01*
G01D02*
X397099Y112905D01*
G01D02*
X395349Y111655D01*
G01D02*
X394561Y110780D01*
G01D02*
X394036Y109530D01*
G01D02*
X393861Y108405D01*
G01D02*
X397536D01*
G01X403199Y115905D02*
X402499Y115655D01*
G01D02*
X401974Y115030D01*
G01D02*
X401624Y114280D01*
G01D02*
X401361Y113280D01*
G01D02*
X401274Y112155D01*
G01D02*
X401361Y111030D01*
G01D02*
X401624Y110030D01*
G01D02*
X401974Y109280D01*
G01D02*
X402499Y108655D01*
G01D02*
X403199Y108405D01*
G01D02*
X403899Y108655D01*
G01D02*
X404424Y109280D01*
G01D02*
X404774Y110030D01*
G01D02*
X405036Y111030D01*
G01D02*
X405124Y112155D01*
G01D02*
X405036Y113280D01*
G01D02*
X404774Y114280D01*
G01D02*
X404424Y115030D01*
G01D02*
X403899Y115655D01*
G01D02*
X403199Y115905D01*
G01X394036Y165305D02*
X394561Y166055D01*
G01X397361Y165680D02*
X397536Y164930D01*
G01D02*
X397449Y164180D01*
G01D02*
X397099Y163555D01*
G01D02*
X395349Y162305D01*
G01D02*
X394561Y161430D01*
G01D02*
X394036Y160180D01*
G01D02*
X393861Y159055D01*
G01D02*
X397536D01*
G01X403199D02*
Y166555D01*
G01D02*
X402149Y165055D01*
G01Y159055D02*
X404249D01*
G01X394561Y166055D02*
X395174Y166430D01*
G01D02*
X395874Y166555D01*
G01D02*
X396749Y166305D01*
G01D02*
X397361Y165680D01*
G01X438962Y99895D02*
X435112Y94395D01*
G01X437037Y93395D02*
Y100895D01*
G01X435112Y99895D02*
X438962Y94395D01*
G01X439662Y97146D02*
X434412D01*
G01X452244Y48957D02*
Y58051D01*
G01X449291Y46004D02*
G03X452244Y48957I0J2953D01*
G01X455197Y61004D02*
G03X452244Y58051I0J-2953D01*
G01X454016Y411201D02*
Y64429D01*
G01X449439Y76949D02*
Y144862D01*
G01X462195Y2539D02*
X532470D01*
G01X462195Y163760D02*
Y2539D01*
G01X455197Y61004D02*
X973199D01*
G01X532470Y163760D02*
X462195D01*
G01X510797Y223572D02*
G03X490718I-10039J14597D01*
G01X477534Y274403D02*
Y282156D01*
G01X492364Y274403D02*
X477534D01*
G01Y266153D02*
Y273906D01*
G01X492364Y266153D02*
X477534D01*
G01Y273906D02*
X492364D01*
G01X483199Y268848D02*
Y271098D01*
G01D02*
X483699D01*
G01D02*
X483859Y270986D01*
G01D02*
X483959Y270836D01*
G01D02*
X483999Y270536D01*
G01D02*
X483959Y270236D01*
G01D02*
X483839Y270048D01*
G01D02*
X483699Y269936D01*
G01D02*
X483199D01*
G01X483699D02*
X483999Y268848D01*
G01X484569Y269786D02*
X484709Y270048D01*
G01D02*
X484829Y270198D01*
G01D02*
X484989Y270273D01*
G01D02*
X485129Y270198D01*
G01D02*
X485229Y270048D01*
G01D02*
X485309Y269823D01*
G01D02*
X485329Y269561D01*
G01D02*
X485309Y269336D01*
G01D02*
X485229Y269111D01*
G01D02*
X485109Y268923D01*
G01D02*
X484969Y268848D01*
G01D02*
X484809Y268923D01*
G01D02*
X484669Y269148D01*
G01D02*
X484589Y269486D01*
G01D02*
X484569Y269861D01*
G01D02*
X484609Y270348D01*
G01D02*
X484669Y270611D01*
G01D02*
X484769Y270873D01*
G01D02*
X484909Y271061D01*
G01D02*
X485049Y271098D01*
G01D02*
X485189Y271023D01*
G01D02*
X485289Y270836D01*
G01X477534Y282156D02*
X492364D01*
G01X477834Y290556D02*
X492664D01*
G01X477834Y282803D02*
Y290556D01*
G01X492664Y282803D02*
X477834D01*
G01Y291053D02*
Y298806D01*
G01X492664Y291053D02*
X477834D01*
G01X483199Y277098D02*
Y279348D01*
G01D02*
X483699D01*
G01D02*
X483859Y279236D01*
G01D02*
X483959Y279086D01*
G01D02*
X483999Y278786D01*
G01D02*
X483959Y278486D01*
G01D02*
X483839Y278298D01*
G01D02*
X483699Y278186D01*
G01D02*
X483199D01*
G01X483699D02*
X483999Y277098D01*
G01X485189D02*
Y279348D01*
G01D02*
X484449Y277736D01*
G01D02*
X485449D01*
G01X483199Y285780D02*
Y288030D01*
G01D02*
X483699D01*
G01D02*
X483859Y287917D01*
G01D02*
X483959Y287767D01*
G01D02*
X483999Y287467D01*
G01D02*
X483959Y287167D01*
G01D02*
X483839Y286980D01*
G01D02*
X483699Y286867D01*
G01D02*
X483199D01*
G01X483699D02*
X483999Y285780D01*
G01X484509Y286230D02*
X484629Y285967D01*
G01D02*
X484789Y285817D01*
G01D02*
X484969Y285780D01*
G01D02*
X485129Y285817D01*
G01D02*
X485289Y286004D01*
G01D02*
X485389Y286230D01*
G01D02*
X485409Y286455D01*
G01D02*
X485369Y286717D01*
G01D02*
X485229Y286904D01*
G01D02*
X485089Y286980D01*
G01D02*
X484909D01*
G01X485089D02*
X485209Y287092D01*
G01D02*
X485309Y287279D01*
G01D02*
X485349Y287504D01*
G01D02*
X485309Y287730D01*
G01D02*
X485209Y287917D01*
G01D02*
X485029Y288030D01*
G01D02*
X484849Y287992D01*
G01D02*
X484669Y287842D01*
G01X477641Y299978D02*
Y307730D01*
G01X492471Y299978D02*
X477641D01*
G01X477834Y298806D02*
X492664D01*
G01X483199Y302280D02*
Y304530D01*
G01D02*
X483699D01*
G01D02*
X483859Y304417D01*
G01D02*
X483959Y304267D01*
G01D02*
X483999Y303967D01*
G01D02*
X483959Y303667D01*
G01D02*
X483839Y303480D01*
G01D02*
X483699Y303367D01*
G01D02*
X483199D01*
G01X483699D02*
X483999Y302280D01*
G01X484509Y302730D02*
X484629Y302467D01*
G01D02*
X484789Y302317D01*
G01D02*
X484969Y302280D01*
G01D02*
X485129Y302317D01*
G01D02*
X485289Y302504D01*
G01D02*
X485389Y302730D01*
G01D02*
X485409Y302955D01*
G01D02*
X485369Y303217D01*
G01D02*
X485229Y303405D01*
G01D02*
X485089Y303480D01*
G01D02*
X484909D01*
G01X485089D02*
X485209Y303592D01*
G01D02*
X485309Y303779D01*
G01D02*
X485349Y304004D01*
G01D02*
X485309Y304230D01*
G01D02*
X485209Y304417D01*
G01D02*
X485029Y304530D01*
G01D02*
X484849Y304492D01*
G01D02*
X484669Y304342D01*
G01X483199Y294030D02*
Y296280D01*
G01D02*
X483699D01*
G01D02*
X483859Y296167D01*
G01D02*
X483959Y296017D01*
G01D02*
X483999Y295717D01*
G01D02*
X483959Y295417D01*
G01D02*
X483839Y295230D01*
G01D02*
X483699Y295117D01*
G01D02*
X483199D01*
G01X483699D02*
X483999Y294030D01*
G01X484509Y294480D02*
X484629Y294217D01*
G01D02*
X484789Y294067D01*
G01D02*
X484969Y294030D01*
G01D02*
X485129Y294067D01*
G01D02*
X485289Y294254D01*
G01D02*
X485389Y294480D01*
G01D02*
X485409Y294705D01*
G01D02*
X485369Y294967D01*
G01D02*
X485229Y295155D01*
G01D02*
X485089Y295230D01*
G01D02*
X484909D01*
G01X485089D02*
X485209Y295342D01*
G01D02*
X485309Y295529D01*
G01D02*
X485349Y295754D01*
G01D02*
X485309Y295980D01*
G01D02*
X485209Y296167D01*
G01D02*
X485029Y296280D01*
G01D02*
X484849Y296242D01*
G01D02*
X484669Y296092D01*
G01X477641Y315530D02*
X492471D01*
G01X477641Y307778D02*
Y315530D01*
G01X492471Y307778D02*
X477641D01*
G01X477834Y316103D02*
Y323856D01*
G01X492664Y316103D02*
X477834D01*
G01X477641Y307730D02*
X492471D01*
G01X483949Y310530D02*
Y312780D01*
G01D02*
X484449D01*
G01D02*
X484609Y312667D01*
G01D02*
X484709Y312517D01*
G01D02*
X484749Y312217D01*
G01D02*
X484709Y311917D01*
G01D02*
X484589Y311730D01*
G01D02*
X484449Y311617D01*
G01D02*
X483949D01*
G01X484449D02*
X484749Y310530D01*
G01X485259Y310980D02*
X485379Y310717D01*
G01D02*
X485539Y310567D01*
G01D02*
X485719Y310530D01*
G01X485779Y312780D02*
X485599Y312742D01*
G01D02*
X485419Y312592D01*
G01X483499Y318798D02*
Y321048D01*
G01D02*
X483999D01*
G01D02*
X484159Y320936D01*
G01D02*
X484259Y320786D01*
G01D02*
X484299Y320486D01*
G01D02*
X484259Y320186D01*
G01D02*
X484139Y319998D01*
G01D02*
X483999Y319886D01*
G01D02*
X483499D01*
G01X483999D02*
X484299Y318798D01*
G01X485489D02*
Y321048D01*
G01D02*
X484749Y319436D01*
G01D02*
X485749D01*
G01X477834Y323856D02*
X492664D01*
G01X477759Y324461D02*
Y332213D01*
G01X492589Y324461D02*
X477759D01*
G01X477834Y333203D02*
Y340956D01*
G01X492664Y333203D02*
X477834D01*
G01X477759Y332213D02*
X492589D01*
G01X483199Y327030D02*
Y329280D01*
G01D02*
X483699D01*
G01D02*
X483859Y329167D01*
G01D02*
X483959Y329017D01*
G01D02*
X483999Y328717D01*
G01D02*
X483959Y328417D01*
G01D02*
X483839Y328230D01*
G01D02*
X483699Y328117D01*
G01D02*
X483199D01*
G01X483699D02*
X483999Y327030D01*
G01X484509Y327367D02*
X484629Y327180D01*
G01D02*
X484769Y327067D01*
G01D02*
X484949Y327030D01*
G01D02*
X485129Y327105D01*
G01D02*
X485269Y327254D01*
G01D02*
X485369Y327517D01*
G01D02*
X485389Y327817D01*
G01D02*
X485349Y328117D01*
G01D02*
X485249Y328305D01*
G01D02*
X485109Y328454D01*
G01D02*
X484969Y328492D01*
G01D02*
X484829Y328454D01*
G01D02*
X484649Y328305D01*
G01D02*
X484709Y329280D01*
G01D02*
X485249D01*
G01X483499Y335898D02*
Y338148D01*
G01D02*
X483999D01*
G01D02*
X484159Y338036D01*
G01D02*
X484259Y337886D01*
G01D02*
X484299Y337586D01*
G01D02*
X484259Y337286D01*
G01D02*
X484139Y337098D01*
G01D02*
X483999Y336986D01*
G01D02*
X483499D01*
G01X483999D02*
X484299Y335898D01*
G01X485489D02*
Y338148D01*
G01D02*
X484749Y336536D01*
G01D02*
X485749D01*
G01X477834Y340956D02*
X492664D01*
G01X477834Y341453D02*
Y349206D01*
G01X492664Y341453D02*
X477834D01*
G01Y349206D02*
X492664D01*
G01X477834Y350153D02*
Y357906D01*
G01X492664Y350153D02*
X477834D01*
G01X483499Y344148D02*
Y346398D01*
G01D02*
X483999D01*
G01D02*
X484159Y346286D01*
G01D02*
X484259Y346136D01*
G01D02*
X484299Y345836D01*
G01D02*
X484259Y345536D01*
G01D02*
X484139Y345348D01*
G01D02*
X483999Y345236D01*
G01D02*
X483499D01*
G01X483999D02*
X484299Y344148D01*
G01X485489D02*
Y346398D01*
G01D02*
X484749Y344786D01*
G01D02*
X485749D01*
G01X483199Y352530D02*
Y354780D01*
G01X483959Y354517D02*
X483999Y354217D01*
G01D02*
X483959Y353917D01*
G01D02*
X483839Y353730D01*
G01D02*
X483699Y353617D01*
G01D02*
X483199D01*
G01X483699D02*
X483999Y352530D01*
G01X484509Y352867D02*
X484629Y352680D01*
G01D02*
X484769Y352567D01*
G01D02*
X484949Y352530D01*
G01D02*
X485129Y352605D01*
G01D02*
X485269Y352754D01*
G01D02*
X485369Y353017D01*
G01D02*
X485389Y353317D01*
G01D02*
X485349Y353617D01*
G01D02*
X485249Y353805D01*
G01D02*
X485109Y353954D01*
G01D02*
X484969Y353992D01*
G01D02*
X484829Y353954D01*
G01D02*
X484649Y353805D01*
G01D02*
X484709Y354780D01*
G01X477834Y357906D02*
X492664D01*
G01X483199Y354780D02*
X483699D01*
G01D02*
X483859Y354667D01*
G01D02*
X483959Y354517D01*
G01X484709Y354780D02*
X485249D01*
G01X487011Y148021D02*
X487449Y147271D01*
G01D02*
X487974Y146771D01*
G01D02*
X488586Y146521D01*
G01D02*
X489286Y146771D01*
G01D02*
X489811Y147271D01*
G01D02*
X490336Y148021D01*
G01D02*
X490511Y149021D01*
G01D02*
Y154021D01*
G01X496261Y146521D02*
Y154021D01*
G01X495211Y146521D02*
X497311D01*
G01X496261Y154021D02*
X495211Y152522D01*
G01X490718Y202736D02*
G03X510797I10039J0D01*
G01X490718D02*
Y223572D01*
G01X492364Y282156D02*
Y274403D01*
G01X485919Y269786D02*
X486059Y270048D01*
G01D02*
X486179Y270198D01*
G01D02*
X486339Y270273D01*
G01D02*
X486479Y270198D01*
G01D02*
X486579Y270048D01*
G01D02*
X486659Y269823D01*
G01D02*
X486679Y269561D01*
G01D02*
X486659Y269336D01*
G01D02*
X486579Y269111D01*
G01D02*
X486459Y268923D01*
G01D02*
X486319Y268848D01*
G01D02*
X486159Y268923D01*
G01D02*
X486019Y269148D01*
G01D02*
X485939Y269486D01*
G01D02*
X485919Y269861D01*
G01D02*
X485959Y270348D01*
G01D02*
X486019Y270611D01*
G01D02*
X486119Y270873D01*
G01D02*
X486259Y271061D01*
G01D02*
X486399Y271098D01*
G01D02*
X486539Y271023D01*
G01D02*
X486639Y270836D01*
G01X492364Y273906D02*
Y266153D01*
G01X486299Y279348D02*
X486139Y279273D01*
G01D02*
X486019Y279086D01*
G01D02*
X485939Y278861D01*
G01D02*
X485879Y278561D01*
G01D02*
X485859Y278223D01*
G01D02*
X485879Y277886D01*
G01D02*
X485939Y277586D01*
G01D02*
X486019Y277361D01*
G01D02*
X486139Y277173D01*
G01D02*
X486299Y277098D01*
G01D02*
X486459Y277173D01*
G01D02*
X486579Y277361D01*
G01D02*
X486659Y277586D01*
G01D02*
X486719Y277886D01*
G01D02*
X486739Y278223D01*
G01D02*
X486719Y278561D01*
G01D02*
X486659Y278861D01*
G01D02*
X486579Y279086D01*
G01D02*
X486459Y279273D01*
G01D02*
X486299Y279348D01*
G01X485859Y286230D02*
X485979Y285967D01*
G01D02*
X486139Y285817D01*
G01D02*
X486319Y285780D01*
G01D02*
X486479Y285817D01*
G01D02*
X486639Y286004D01*
G01D02*
X486739Y286230D01*
G01D02*
X486759Y286455D01*
G01D02*
X486719Y286717D01*
G01D02*
X486579Y286904D01*
G01D02*
X486439Y286980D01*
G01D02*
X486259D01*
G01X486439D02*
X486559Y287092D01*
G01D02*
X486659Y287279D01*
G01D02*
X486699Y287504D01*
G01D02*
X486659Y287730D01*
G01D02*
X486559Y287917D01*
G01D02*
X486379Y288030D01*
G01D02*
X486199Y287992D01*
G01D02*
X486019Y287842D01*
G01X492664Y290556D02*
Y282803D01*
G01Y298806D02*
Y291053D01*
G01X486299Y304530D02*
X486139Y304455D01*
G01D02*
X486019Y304267D01*
G01D02*
X485939Y304042D01*
G01D02*
X485879Y303742D01*
G01D02*
X485859Y303405D01*
G01D02*
X485879Y303067D01*
G01D02*
X485939Y302767D01*
G01D02*
X486019Y302542D01*
G01D02*
X486139Y302355D01*
G01D02*
X486299Y302280D01*
G01D02*
X486459Y302355D01*
G01D02*
X486579Y302542D01*
G01D02*
X486659Y302767D01*
G01D02*
X486719Y303067D01*
G01D02*
X486739Y303405D01*
G01D02*
X486719Y303742D01*
G01D02*
X486659Y304042D01*
G01D02*
X486579Y304267D01*
G01D02*
X486459Y304455D01*
G01D02*
X486299Y304530D01*
G01X492471Y307730D02*
Y299978D01*
G01X485919Y295905D02*
X486039Y296130D01*
G01D02*
X486179Y296242D01*
G01D02*
X486339Y296280D01*
G01D02*
X486539Y296205D01*
G01D02*
X486679Y296017D01*
G01D02*
X486719Y295792D01*
G01D02*
X486699Y295567D01*
G01D02*
X486619Y295380D01*
G01D02*
X486219Y295005D01*
G01D02*
X486039Y294742D01*
G01D02*
X485919Y294367D01*
G01D02*
X485879Y294030D01*
G01D02*
X486719D01*
G01X485719Y310530D02*
X485879Y310567D01*
G01D02*
X486039Y310754D01*
G01D02*
X486139Y310980D01*
G01D02*
X486159Y311205D01*
G01D02*
X486119Y311467D01*
G01D02*
X485979Y311655D01*
G01D02*
X485839Y311730D01*
G01D02*
X485659D01*
G01X485839D02*
X485959Y311842D01*
G01D02*
X486059Y312029D01*
G01D02*
X486099Y312254D01*
G01D02*
X486059Y312480D01*
G01D02*
X485959Y312667D01*
G01D02*
X485779Y312780D01*
G01X487049Y310530D02*
Y312780D01*
G01D02*
X486809Y312330D01*
G01Y310530D02*
X487289D01*
G01X492471Y315530D02*
Y307778D01*
G01X486219Y320673D02*
X486339Y320898D01*
G01D02*
X486479Y321011D01*
G01D02*
X486639Y321048D01*
G01D02*
X486839Y320973D01*
G01D02*
X486979Y320786D01*
G01D02*
X487019Y320561D01*
G01D02*
X486999Y320336D01*
G01D02*
X486919Y320148D01*
G01D02*
X486519Y319773D01*
G01D02*
X486339Y319511D01*
G01D02*
X486219Y319136D01*
G01D02*
X486179Y318798D01*
G01D02*
X487019D01*
G01X492664Y323856D02*
Y316103D01*
G01X485859Y327367D02*
X485979Y327180D01*
G01D02*
X486119Y327067D01*
G01D02*
X486299Y327030D01*
G01D02*
X486479Y327105D01*
G01D02*
X486619Y327254D01*
G01D02*
X486719Y327517D01*
G01D02*
X486739Y327817D01*
G01D02*
X486699Y328117D01*
G01D02*
X486599Y328305D01*
G01D02*
X486459Y328454D01*
G01D02*
X486319Y328492D01*
G01D02*
X486179Y328454D01*
G01D02*
X485999Y328305D01*
G01D02*
X486059Y329280D01*
G01D02*
X486599D01*
G01X492589Y332213D02*
Y324461D01*
G01X486839Y335898D02*
Y338148D01*
G01D02*
X486099Y336536D01*
G01D02*
X487099D01*
G01X492664Y340956D02*
Y333203D01*
G01X486159Y344598D02*
X486279Y344336D01*
G01D02*
X486439Y344186D01*
G01D02*
X486619Y344148D01*
G01D02*
X486779Y344186D01*
G01D02*
X486939Y344373D01*
G01D02*
X487039Y344598D01*
G01D02*
X487059Y344823D01*
G01D02*
X487019Y345086D01*
G01D02*
X486879Y345273D01*
G01D02*
X486739Y345348D01*
G01D02*
X486559D01*
G01X486739D02*
X486859Y345461D01*
G01D02*
X486959Y345648D01*
G01D02*
X486999Y345873D01*
G01D02*
X486959Y346098D01*
G01D02*
X486859Y346286D01*
G01D02*
X486679Y346398D01*
G01D02*
X486499Y346361D01*
G01D02*
X486319Y346211D01*
G01X492664Y349206D02*
Y341453D01*
G01X486259Y352530D02*
X486299Y353017D01*
G01D02*
X486359Y353429D01*
G01D02*
X486439Y353805D01*
G01D02*
X486539Y354217D01*
G01D02*
X486699Y354780D01*
G01X492664Y357906D02*
Y350153D01*
G01X486699Y354780D02*
X485899D01*
G01X502274Y147396D02*
X502886Y146771D01*
G01D02*
X503586Y146521D01*
G01D02*
X504286Y146771D01*
G01D02*
X504899Y147521D01*
G01D02*
X505336Y148646D01*
G01D02*
X505511Y149771D01*
G01X502624D02*
X503149Y149271D01*
G01D02*
X503761Y149146D01*
G01D02*
X504461Y149396D01*
G01D02*
X504986Y150021D01*
G01X505511Y149771D02*
Y151146D01*
G01D02*
X505336Y152271D01*
G01D02*
X504899Y153271D01*
G01D02*
X504374Y153771D01*
G01D02*
X503761Y154021D01*
G01D02*
X503061Y153771D01*
G01D02*
X502536Y153271D01*
G01D02*
X502186Y152522D01*
G01D02*
X502011Y151521D01*
G01D02*
X502186Y150646D01*
G01D02*
X502624Y149771D01*
G01X504986Y150021D02*
X505511Y151146D01*
G01X510797Y223572D02*
Y202736D01*
G01X511699Y264461D02*
Y266711D01*
G01D02*
X512199D01*
G01D02*
X512359Y266598D01*
G01D02*
X512459Y266448D01*
G01D02*
X512499Y266148D01*
G01D02*
X512459Y265848D01*
G01D02*
X512339Y265661D01*
G01D02*
X512199Y265548D01*
G01D02*
X511699D01*
G01X512199D02*
X512499Y264461D01*
G01X513009Y264798D02*
X513129Y264611D01*
G01D02*
X513269Y264498D01*
G01D02*
X513449Y264461D01*
G01D02*
X513629Y264536D01*
G01D02*
X513769Y264686D01*
G01D02*
X513869Y264948D01*
G01D02*
X513889Y265248D01*
G01D02*
X513849Y265548D01*
G01D02*
X513749Y265736D01*
G01D02*
X513609Y265886D01*
G01D02*
X513469Y265923D01*
G01D02*
X513329Y265886D01*
G01D02*
X513149Y265736D01*
G01D02*
X513209Y266711D01*
G01D02*
X513749D01*
G01X515039Y264461D02*
Y266711D01*
G01D02*
X514299Y265098D01*
G01D02*
X515299D01*
G01X506034Y268656D02*
X520864D01*
G01X506034Y260903D02*
Y268656D01*
G01X520864Y260903D02*
X506034D01*
G01X511699Y272711D02*
Y274961D01*
G01D02*
X512199D01*
G01D02*
X512359Y274848D01*
G01D02*
X512459Y274698D01*
G01D02*
X512499Y274398D01*
G01D02*
X512459Y274098D01*
G01D02*
X512339Y273911D01*
G01D02*
X512199Y273798D01*
G01D02*
X511699D01*
G01X512199D02*
X512499Y272711D01*
G01X513009Y273048D02*
X513129Y272861D01*
G01D02*
X513269Y272748D01*
G01D02*
X513449Y272711D01*
G01D02*
X513629Y272786D01*
G01D02*
X513769Y272936D01*
G01D02*
X513869Y273198D01*
G01D02*
X513889Y273498D01*
G01D02*
X513849Y273798D01*
G01D02*
X513749Y273986D01*
G01D02*
X513609Y274136D01*
G01D02*
X513469Y274173D01*
G01D02*
X513329Y274136D01*
G01D02*
X513149Y273986D01*
G01D02*
X513209Y274961D01*
G01D02*
X513749D01*
G01X514419Y273648D02*
X514559Y273911D01*
G01D02*
X514679Y274061D01*
G01D02*
X514839Y274136D01*
G01D02*
X514979Y274061D01*
G01D02*
X515079Y273911D01*
G01D02*
X515159Y273686D01*
G01D02*
X515179Y273423D01*
G01D02*
X515159Y273198D01*
G01D02*
X515079Y272973D01*
G01D02*
X514959Y272786D01*
G01D02*
X514819Y272711D01*
G01D02*
X514659Y272786D01*
G01D02*
X514519Y273011D01*
G01D02*
X514439Y273348D01*
G01D02*
X514419Y273723D01*
G01D02*
X514459Y274211D01*
G01D02*
X514519Y274473D01*
G01D02*
X514619Y274736D01*
G01D02*
X514759Y274923D01*
G01D02*
X514899Y274961D01*
G01D02*
X515039Y274886D01*
G01D02*
X515139Y274698D01*
G01X506034Y269153D02*
Y276906D01*
G01X520864Y269153D02*
X506034D01*
G01X505734Y280403D02*
Y288156D01*
G01X520564Y280403D02*
X505734D01*
G01X506034Y276906D02*
X520864D01*
G01X505734Y288653D02*
Y296406D01*
G01X520564Y288653D02*
X505734D01*
G01X511399Y283098D02*
Y285348D01*
G01D02*
X511899D01*
G01D02*
X512059Y285236D01*
G01D02*
X512159Y285086D01*
G01D02*
X512199Y284786D01*
G01D02*
X512159Y284486D01*
G01D02*
X512039Y284298D01*
G01D02*
X511899Y284186D01*
G01D02*
X511399D01*
G01X511899D02*
X512199Y283098D01*
G01X512709Y283436D02*
X512829Y283248D01*
G01D02*
X512969Y283136D01*
G01D02*
X513149Y283098D01*
G01D02*
X513329Y283173D01*
G01D02*
X513469Y283323D01*
G01D02*
X513569Y283586D01*
G01D02*
X513589Y283886D01*
G01D02*
X513549Y284186D01*
G01D02*
X513449Y284373D01*
G01D02*
X513309Y284523D01*
G01D02*
X513169Y284561D01*
G01D02*
X513029Y284523D01*
G01D02*
X512849Y284373D01*
G01D02*
X512909Y285348D01*
G01D02*
X513449D01*
G01X514499D02*
X514339Y285273D01*
G01D02*
X514219Y285086D01*
G01D02*
X514139Y284861D01*
G01D02*
X514079Y284561D01*
G01D02*
X514059Y284223D01*
G01D02*
X514079Y283886D01*
G01D02*
X514139Y283586D01*
G01D02*
X514219Y283361D01*
G01D02*
X514339Y283173D01*
G01D02*
X514499Y283098D01*
G01D02*
X514659Y283173D01*
G01D02*
X514779Y283361D01*
G01D02*
X514859Y283586D01*
G01D02*
X514919Y283886D01*
G01D02*
X514939Y284223D01*
G01D02*
X514919Y284561D01*
G01D02*
X514859Y284861D01*
G01D02*
X514779Y285086D01*
G01D02*
X514659Y285273D01*
G01D02*
X514499Y285348D01*
G01X505734Y288156D02*
X520564D01*
G01X502555Y296528D02*
Y307280D01*
G01X520658Y296528D02*
X502555D01*
G01X510696Y303352D02*
X510576Y303465D01*
G01D02*
X510436Y303540D01*
G01D02*
X510276D01*
G01D02*
X510096Y303427D01*
G01D02*
X509956Y303240D01*
G01D02*
X509856Y303015D01*
G01D02*
X509776Y302640D01*
G01D02*
X509756Y302302D01*
G01D02*
X509796Y301965D01*
G01D02*
X509856Y301740D01*
G01D02*
X509976Y301515D01*
G01D02*
X510116Y301365D01*
G01D02*
X510256Y301290D01*
G01D02*
X510396D01*
G01D02*
X510536Y301365D01*
G01D02*
X510656Y301477D01*
G01D02*
X510756Y301627D01*
G01X511226Y303165D02*
X511346Y303390D01*
G01D02*
X511486Y303502D01*
G01D02*
X511646Y303540D01*
G01D02*
X511846Y303465D01*
G01D02*
X511986Y303277D01*
G01D02*
X512026Y303052D01*
G01D02*
X512006Y302827D01*
G01D02*
X511926Y302640D01*
G01D02*
X511526Y302265D01*
G01D02*
X511346Y302002D01*
G01D02*
X511226Y301627D01*
G01D02*
X511186Y301290D01*
G01D02*
X512026D01*
G01X512916D02*
X512956Y301777D01*
G01D02*
X513016Y302190D01*
G01D02*
X513096Y302565D01*
G01D02*
X513196Y302977D01*
G01D02*
X513356Y303540D01*
G01D02*
X512556D01*
G01X511399Y292211D02*
Y294461D01*
G01D02*
X511899D01*
G01D02*
X512059Y294348D01*
G01D02*
X512159Y294198D01*
G01D02*
X512199Y293898D01*
G01D02*
X512159Y293598D01*
G01D02*
X512039Y293411D01*
G01D02*
X511899Y293298D01*
G01D02*
X511399D01*
G01X511899D02*
X512199Y292211D01*
G01X512709Y292548D02*
X512829Y292361D01*
G01D02*
X512969Y292248D01*
G01D02*
X513149Y292211D01*
G01D02*
X513329Y292286D01*
G01D02*
X513469Y292436D01*
G01D02*
X513569Y292698D01*
G01D02*
X513589Y292998D01*
G01D02*
X513549Y293298D01*
G01D02*
X513449Y293486D01*
G01D02*
X513309Y293636D01*
G01D02*
X513169Y293673D01*
G01D02*
X513029Y293636D01*
G01D02*
X512849Y293486D01*
G01D02*
X512909Y294461D01*
G01D02*
X513449D01*
G01X514499Y292211D02*
Y294461D01*
G01D02*
X514259Y294011D01*
G01Y292211D02*
X514739D01*
G01X505734Y296406D02*
X520564D01*
G01X502555Y307280D02*
X520658D01*
G01X511806Y321085D02*
Y323335D01*
G01X512566Y323073D02*
X512606Y322773D01*
G01D02*
X512566Y322473D01*
G01D02*
X512446Y322285D01*
G01D02*
X512306Y322172D01*
G01D02*
X511806D01*
G01X512306D02*
X512606Y321085D01*
G01X513796D02*
Y323335D01*
G01D02*
X513056Y321723D01*
G01D02*
X514056D01*
G01X514566Y321347D02*
X514706Y321160D01*
G01D02*
X514866Y321085D01*
G01D02*
X515026Y321160D01*
G01D02*
X515166Y321385D01*
G01D02*
X515266Y321723D01*
G01D02*
X515306Y322060D01*
G01D02*
Y322473D01*
G01D02*
X515266Y322810D01*
G01D02*
X515166Y323110D01*
G01X514546Y322885D02*
X514506Y322585D01*
G01D02*
X514546Y322323D01*
G01D02*
X514646Y322060D01*
G01D02*
X514766Y321910D01*
G01D02*
X514906Y321872D01*
G01D02*
X515066Y321947D01*
G01D02*
X515186Y322135D01*
G01D02*
X515306Y322473D01*
G01X506141Y317528D02*
Y325280D01*
G01X520971Y317528D02*
X506141D01*
G01X511806Y312423D02*
Y314673D01*
G01D02*
X512306D01*
G01D02*
X512466Y314560D01*
G01D02*
X512566Y314410D01*
G01D02*
X512606Y314110D01*
G01D02*
X512566Y313810D01*
G01D02*
X512446Y313623D01*
G01D02*
X512306Y313510D01*
G01D02*
X511806D01*
G01X512306D02*
X512606Y312423D01*
G01X513796D02*
Y314673D01*
G01D02*
X513056Y313060D01*
G01D02*
X514056D01*
G01X514906Y312423D02*
X515046Y312460D01*
G01D02*
X515206Y312573D01*
G01D02*
X515306Y312760D01*
G01D02*
X515346Y313023D01*
G01D02*
X515306Y313285D01*
G01D02*
X515186Y313510D01*
G01D02*
X515006Y313623D01*
G01D02*
X514806D01*
G01D02*
X514686Y313698D01*
G01D02*
X514586Y313885D01*
G01D02*
X514546Y314148D01*
G01D02*
X514606Y314410D01*
G01D02*
X514746Y314598D01*
G01D02*
X514906Y314673D01*
G01D02*
X515066Y314598D01*
G01D02*
X515206Y314410D01*
G01D02*
X515266Y314148D01*
G01D02*
X515226Y313885D01*
G01D02*
X515126Y313698D01*
G01D02*
X515006Y313623D01*
G01D02*
X514806D01*
G01D02*
X514626Y313510D01*
G01D02*
X514506Y313285D01*
G01D02*
X514466Y313023D01*
G01D02*
X514506Y312760D01*
G01D02*
X514606Y312573D01*
G01D02*
X514766Y312460D01*
G01D02*
X514906Y312423D01*
G01X506141Y309728D02*
Y317480D01*
G01X520971Y309728D02*
X506141D01*
G01Y317480D02*
X520971D01*
G01X511806Y323335D02*
X512306D01*
G01D02*
X512466Y323222D01*
G01D02*
X512566Y323073D01*
G01X515166Y323110D02*
X515046Y323260D01*
G01D02*
X514906Y323335D01*
G01D02*
X514746Y323260D01*
G01D02*
X514626Y323110D01*
G01D02*
X514546Y322885D01*
G01X506141Y325280D02*
X520971D01*
G01X512449Y330030D02*
Y332280D01*
G01D02*
X512949D01*
G01D02*
X513109Y332167D01*
G01D02*
X513209Y332017D01*
G01D02*
X513249Y331717D01*
G01D02*
X513209Y331417D01*
G01D02*
X513089Y331230D01*
G01D02*
X512949Y331117D01*
G01D02*
X512449D01*
G01X512949D02*
X513249Y330030D01*
G01X513759Y330367D02*
X513879Y330180D01*
G01D02*
X514019Y330067D01*
G01D02*
X514199Y330030D01*
G01D02*
X514379Y330105D01*
G01D02*
X514519Y330254D01*
G01D02*
X514619Y330517D01*
G01D02*
X514639Y330817D01*
G01D02*
X514599Y331117D01*
G01D02*
X514499Y331305D01*
G01D02*
X514359Y331455D01*
G01D02*
X514219Y331492D01*
G01D02*
X514079Y331455D01*
G01D02*
X513899Y331305D01*
G01D02*
X513959Y332280D01*
G01D02*
X514499D01*
G01X515109Y330480D02*
X515229Y330217D01*
G01D02*
X515389Y330067D01*
G01D02*
X515569Y330030D01*
G01D02*
X515729Y330067D01*
G01D02*
X515889Y330254D01*
G01D02*
X515989Y330480D01*
G01D02*
X516009Y330705D01*
G01D02*
X515969Y330967D01*
G01D02*
X515829Y331154D01*
G01D02*
X515689Y331230D01*
G01D02*
X515509D01*
G01X515689D02*
X515809Y331342D01*
G01D02*
X515909Y331529D01*
G01D02*
X515949Y331754D01*
G01D02*
X515909Y331980D01*
G01D02*
X515809Y332167D01*
G01D02*
X515629Y332280D01*
G01D02*
X515449Y332242D01*
G01D02*
X515269Y332092D01*
G01X505926Y325779D02*
Y333532D01*
G01X520756Y325779D02*
X505926D01*
G01Y333532D02*
X520756D01*
G01X511699Y336780D02*
Y339030D01*
G01X512459Y338767D02*
X512499Y338467D01*
G01D02*
X512459Y338167D01*
G01D02*
X512339Y337980D01*
G01D02*
X512199Y337867D01*
G01D02*
X511699D01*
G01X512199D02*
X512499Y336780D01*
G01X513009Y337117D02*
X513129Y336930D01*
G01D02*
X513269Y336817D01*
G01D02*
X513449Y336780D01*
G01D02*
X513629Y336855D01*
G01D02*
X513769Y337004D01*
G01D02*
X513869Y337267D01*
G01D02*
X513889Y337567D01*
G01D02*
X513849Y337867D01*
G01D02*
X513749Y338055D01*
G01D02*
X513609Y338204D01*
G01D02*
X513469Y338242D01*
G01D02*
X513329Y338204D01*
G01D02*
X513149Y338055D01*
G01D02*
X513209Y339030D01*
G01X515179Y338767D02*
X515219Y338542D01*
G01D02*
X515199Y338317D01*
G01D02*
X515119Y338130D01*
G01D02*
X514719Y337755D01*
G01D02*
X514539Y337492D01*
G01D02*
X514419Y337117D01*
G01D02*
X514379Y336780D01*
G01D02*
X515219D01*
G01X505926Y334029D02*
Y341782D01*
G01X520756Y334029D02*
X505926D01*
G01X511806Y353335D02*
Y355585D01*
G01X512306Y354422D02*
X512606Y353335D01*
G01X513796D02*
Y355585D01*
G01D02*
X513056Y353973D01*
G01D02*
X514056D01*
G01X514866Y353335D02*
X514906Y353822D01*
G01D02*
X514966Y354235D01*
G01D02*
X515046Y354610D01*
G01X506141Y349778D02*
Y357530D01*
G01X520971Y349778D02*
X506141D01*
G01X511806Y344673D02*
Y346923D01*
G01D02*
X512306D01*
G01D02*
X512466Y346810D01*
G01D02*
X512566Y346660D01*
G01D02*
X512606Y346360D01*
G01D02*
X512566Y346060D01*
G01D02*
X512446Y345873D01*
G01D02*
X512306Y345760D01*
G01D02*
X511806D01*
G01X512306D02*
X512606Y344673D01*
G01X513796D02*
Y346923D01*
G01D02*
X513056Y345310D01*
G01D02*
X514056D01*
G01X514526Y345610D02*
X514666Y345873D01*
G01D02*
X514786Y346023D01*
G01D02*
X514946Y346098D01*
G01D02*
X515086Y346023D01*
G01D02*
X515186Y345873D01*
G01D02*
X515266Y345648D01*
G01D02*
X515286Y345385D01*
G01D02*
X515266Y345160D01*
G01D02*
X515186Y344935D01*
G01D02*
X515066Y344748D01*
G01D02*
X514926Y344673D01*
G01D02*
X514766Y344748D01*
G01D02*
X514626Y344973D01*
G01D02*
X514546Y345310D01*
G01D02*
X514526Y345685D01*
G01D02*
X514566Y346173D01*
G01D02*
X514626Y346435D01*
G01D02*
X514726Y346698D01*
G01D02*
X514866Y346885D01*
G01D02*
X515006Y346923D01*
G01D02*
X515146Y346848D01*
G01D02*
X515246Y346660D01*
G01X506141Y341978D02*
Y349730D01*
G01X520971Y341978D02*
X506141D01*
G01Y349730D02*
X520971D01*
G01X511699Y339030D02*
X512199D01*
G01D02*
X512359Y338917D01*
G01D02*
X512459Y338767D01*
G01X513209Y339030D02*
X513749D01*
G01X514419Y338655D02*
X514539Y338880D01*
G01D02*
X514679Y338992D01*
G01D02*
X514839Y339030D01*
G01D02*
X515039Y338955D01*
G01D02*
X515179Y338767D01*
G01X505926Y341782D02*
X520756D01*
G01X511806Y355585D02*
X512306D01*
G01D02*
X512466Y355472D01*
G01D02*
X512566Y355323D01*
G01D02*
X512606Y355023D01*
G01D02*
X512566Y354723D01*
G01D02*
X512446Y354535D01*
G01D02*
X512306Y354422D01*
G01D02*
X511806D01*
G01X515046Y354610D02*
X515146Y355023D01*
G01D02*
X515306Y355585D01*
G01D02*
X514506D01*
G01X506141Y357530D02*
X520971D01*
G01X532470Y2539D02*
Y163760D01*
G01X528785Y76136D02*
X524935Y70636D01*
G01X526860Y69636D02*
Y77136D01*
G01X524935Y76136D02*
X528785Y70636D01*
G01X529485Y73386D02*
X524235D01*
G01X520864Y268656D02*
Y260903D01*
G01Y276906D02*
Y269153D01*
G01X520564Y288156D02*
Y280403D01*
G01Y296406D02*
Y288653D01*
G01X520658Y307280D02*
Y296528D01*
G01X520971Y325280D02*
Y317528D01*
G01Y317480D02*
Y309728D01*
G01X520756Y333532D02*
Y325779D01*
G01Y341782D02*
Y334029D01*
G01X520971Y357530D02*
Y349778D01*
G01Y349730D02*
Y341978D01*
G01X545699Y114626D02*
X641368D01*
G01X545699Y402343D02*
Y114626D01*
G01X641368Y402343D02*
X545699D01*
G01X562731Y74256D02*
Y68303D01*
G01D02*
X574567D01*
G01Y74256D02*
X562731D01*
G01X561053Y129213D02*
X620108D01*
G01X561053Y174685D02*
Y129213D01*
G01X626014Y174685D02*
X561053D01*
G01X566769Y69780D02*
Y72030D01*
G01X568079Y70079D02*
X568239Y69892D01*
G01D02*
X568419Y69780D01*
G01D02*
X568579D01*
G01D02*
X568739Y69892D01*
G01D02*
X568859Y70079D01*
G01D02*
X568919Y70342D01*
G01D02*
X568879Y70604D01*
G01D02*
X568779Y70830D01*
G01D02*
X568599Y70980D01*
G01X569409Y70230D02*
X569529Y69967D01*
G01D02*
X569689Y69817D01*
G01D02*
X569869Y69780D01*
G01D02*
X570029Y69817D01*
G01D02*
X570189Y70004D01*
G01D02*
X570289Y70230D01*
G01D02*
X570309Y70455D01*
G01D02*
X570269Y70717D01*
G01D02*
X570129Y70904D01*
G01X574567Y68303D02*
Y74256D01*
G01X577349Y74280D02*
Y68280D01*
G01D02*
X589349D01*
G01X566769Y72030D02*
X567529D01*
G01X567249Y70942D02*
X566769D01*
G01X568599Y70980D02*
X568359Y71055D01*
G01D02*
X568219Y71204D01*
G01D02*
X568159Y71467D01*
G01D02*
X568199Y71730D01*
G01D02*
X568299Y71917D01*
G01D02*
X568439Y72030D01*
G01D02*
X568579D01*
G01D02*
X568719Y71955D01*
G01D02*
X568839Y71767D01*
G01X570129Y70904D02*
X569989Y70980D01*
G01D02*
X569809D01*
G01X569989D02*
X570109Y71092D01*
G01D02*
X570209Y71279D01*
G01D02*
X570249Y71504D01*
G01D02*
X570209Y71730D01*
G01D02*
X570109Y71917D01*
G01D02*
X569929Y72030D01*
G01D02*
X569749Y71992D01*
G01D02*
X569569Y71842D01*
G01X576923Y82328D02*
X588726D01*
G01X576923Y88280D02*
Y82328D01*
G01Y75578D02*
X588726D01*
G01X576923Y81530D02*
Y75578D01*
G01X588726Y81530D02*
X576923D01*
G01X589349Y74280D02*
X577349D01*
G01X588726Y88280D02*
X576923D01*
G01X581843Y69555D02*
Y71805D01*
G01X582323Y70718D02*
X581843D01*
G01X583733Y70755D02*
X583813Y70868D01*
G01X583113Y71805D02*
Y69555D01*
G01D02*
X583773D01*
G01D02*
X583913Y69705D01*
G01D02*
X583993Y69930D01*
G01D02*
X584033Y70193D01*
G01D02*
X583993Y70455D01*
G01D02*
X583873Y70680D01*
G01D02*
X583733Y70755D01*
G01D02*
X583113D01*
G01X584483Y70005D02*
X584603Y69743D01*
G01D02*
X584763Y69593D01*
G01D02*
X584943Y69555D01*
G01D02*
X585103Y69593D01*
G01D02*
X585263Y69780D01*
G01D02*
X585363Y70005D01*
G01D02*
X585383Y70230D01*
G01D02*
X585343Y70493D01*
G01D02*
X585203Y70680D01*
G01D02*
X585063Y70755D01*
G01D02*
X584883D01*
G01X585063D02*
X585183Y70868D01*
G01X589349Y68280D02*
Y74280D01*
G01X597201Y68889D02*
X589448D01*
G01D02*
Y83719D01*
G01X581843Y71805D02*
X582603D01*
G01X583813Y70868D02*
X583873Y71055D01*
G01D02*
X583913Y71318D01*
G01D02*
X583873Y71543D01*
G01D02*
X583793Y71693D01*
G01D02*
X583653Y71805D01*
G01D02*
X583113D01*
G01X585183Y70868D02*
X585283Y71055D01*
G01D02*
X585323Y71280D01*
G01D02*
X585283Y71505D01*
G01D02*
X585183Y71693D01*
G01D02*
X585003Y71805D01*
G01D02*
X584823Y71768D01*
G01D02*
X584643Y71618D01*
G01X581174Y86787D02*
X581074Y86562D01*
G01D02*
X580994Y86187D01*
G01D02*
X580974Y85850D01*
G01D02*
X581014Y85512D01*
G01D02*
X581074Y85287D01*
G01D02*
X581194Y85062D01*
G01D02*
X581334Y84912D01*
G01D02*
X581474Y84837D01*
G01D02*
X581614D01*
G01D02*
X581754Y84912D01*
G01D02*
X581874Y85025D01*
G01D02*
X581974Y85175D01*
G01X582824Y84837D02*
Y87087D01*
G01X582584Y84837D02*
X583064D01*
G01X584174D02*
Y87087D01*
G01X583934Y84837D02*
X584414D01*
G01X588726Y82328D02*
Y88280D01*
G01X581914Y80150D02*
X581794Y80262D01*
G01D02*
X581654Y80337D01*
G01D02*
X581494D01*
G01D02*
X581314Y80225D01*
G01D02*
X581174Y80037D01*
G01D02*
X581074Y79812D01*
G01D02*
X580994Y79437D01*
G01D02*
X580974Y79100D01*
G01D02*
X581014Y78762D01*
G01D02*
X581074Y78537D01*
G01D02*
X581194Y78312D01*
G01D02*
X581334Y78162D01*
G01D02*
X581474Y78087D01*
G01D02*
X581614D01*
G01D02*
X581754Y78162D01*
G01D02*
X581874Y78275D01*
G01D02*
X581974Y78425D01*
G01X582824Y78087D02*
Y80337D01*
G01D02*
X582584Y79887D01*
G01Y78087D02*
X583064D01*
G01X583794Y79962D02*
X583914Y80187D01*
G01D02*
X584054Y80300D01*
G01D02*
X584214Y80337D01*
G01D02*
X584414Y80262D01*
G01D02*
X584554Y80075D01*
G01D02*
X584594Y79850D01*
G01D02*
X584574Y79625D01*
G01D02*
X584494Y79437D01*
G01D02*
X584094Y79062D01*
G01D02*
X583914Y78800D01*
G01D02*
X583794Y78425D01*
G01D02*
X583754Y78087D01*
G01D02*
X584594D01*
G01X588726Y75578D02*
Y81530D01*
G01X594505Y74554D02*
X592255D01*
G01D02*
Y75054D01*
G01D02*
X592368Y75214D01*
G01D02*
X592518Y75314D01*
G01D02*
X592818Y75354D01*
G01D02*
X593118Y75314D01*
G01D02*
X593305Y75194D01*
G01D02*
X593418Y75054D01*
G01D02*
Y74554D01*
G01Y75054D02*
X594505Y75354D01*
G01Y76544D02*
X592255D01*
G01D02*
X593868Y75804D01*
G01D02*
Y76804D01*
G01X594505Y77654D02*
X592255D01*
G01D02*
X592705Y77414D01*
G01X594505D02*
Y77894D01*
G01X589448Y83719D02*
X597201D01*
G01X581914Y86900D02*
X581794Y87012D01*
G01D02*
X581654Y87087D01*
G01D02*
X581494D01*
G01D02*
X581314Y86975D01*
G01D02*
X581174Y86787D01*
G01X582824Y87087D02*
X582584Y86637D01*
G01X584174Y87087D02*
X583934Y86637D01*
G01X595458Y121195D02*
X591608Y115695D01*
G01X593534Y114695D02*
Y122195D01*
G01X591608Y121195D02*
X595458Y115695D01*
G01X596158Y118445D02*
X590908D01*
G01X584283Y151992D02*
X584721Y151242D01*
G01D02*
X585246Y150742D01*
G01D02*
X585858Y150492D01*
G01D02*
X586558Y150742D01*
G01D02*
X587083Y151242D01*
G01D02*
X587609Y151992D01*
G01D02*
X587783Y152992D01*
G01D02*
Y157992D01*
G01X593533Y150492D02*
Y157992D01*
G01D02*
X592483Y156492D01*
G01Y150492D02*
X594583D01*
G01X584283Y229945D02*
X584721Y229195D01*
G01D02*
X585246Y228695D01*
G01D02*
X585858Y228445D01*
G01D02*
X586558Y228695D01*
G01D02*
X587083Y229195D01*
G01D02*
X587609Y229945D01*
G01D02*
X587783Y230945D01*
G01D02*
Y235945D01*
G01X593533Y228445D02*
Y235945D01*
G01D02*
X592483Y234445D01*
G01Y228445D02*
X594583D01*
G01X597201Y83719D02*
Y68889D01*
G01X597698D02*
Y83719D01*
G01X605451Y68889D02*
X597698D01*
G01X606074Y74804D02*
Y68804D01*
G01D02*
X618074D01*
G01X605451Y83719D02*
Y68889D01*
G01X609819Y70830D02*
Y73080D01*
G01X611089D02*
Y70830D01*
G01D02*
X611749D01*
G01X601893Y74554D02*
X599643D01*
G01D02*
Y75054D01*
G01D02*
X599756Y75214D01*
G01D02*
X599906Y75314D01*
G01D02*
X600206Y75354D01*
G01D02*
X600506Y75314D01*
G01D02*
X600693Y75194D01*
G01D02*
X600806Y75054D01*
G01D02*
Y74554D01*
G01Y75054D02*
X601893Y75354D01*
G01Y76544D02*
X599643D01*
G01D02*
X601256Y75804D01*
G01D02*
Y76804D01*
G01X601556Y77214D02*
X601743Y77334D01*
G01D02*
X601856Y77474D01*
G01D02*
X601893Y77654D01*
G01D02*
X601818Y77834D01*
G01D02*
X601668Y77974D01*
G01D02*
X601406Y78074D01*
G01D02*
X601106Y78094D01*
G01D02*
X600806Y78054D01*
G01D02*
X600618Y77954D01*
G01D02*
X600468Y77814D01*
G01D02*
X600431Y77674D01*
G01D02*
X600468Y77534D01*
G01D02*
X600618Y77354D01*
G01D02*
X599643Y77414D01*
G01D02*
Y77954D01*
G01X597698Y83719D02*
X605451D01*
G01X611164Y79583D02*
X611044Y79695D01*
G01D02*
X610904Y79770D01*
G01D02*
X610744D01*
G01D02*
X610564Y79658D01*
G01D02*
X610424Y79470D01*
G01D02*
X610324Y79245D01*
G01D02*
X610244Y78870D01*
G01D02*
X610224Y78533D01*
G01D02*
X610264Y78195D01*
G01D02*
X610324Y77970D01*
G01D02*
X610444Y77745D01*
G01D02*
X610584Y77595D01*
G01D02*
X610724Y77520D01*
G01D02*
X610864D01*
G01D02*
X611004Y77595D01*
G01D02*
X611124Y77708D01*
G01D02*
X611224Y77858D01*
G01X606173Y81530D02*
Y75578D01*
G01X617976Y81530D02*
X606173D01*
G01Y75578D02*
X617976D01*
G01X611719Y86445D02*
X611579Y86520D01*
G01D02*
X611419D01*
G01D02*
X611239Y86408D01*
G01D02*
X611099Y86220D01*
G01D02*
X610999Y85995D01*
G01D02*
X610919Y85620D01*
G01D02*
X610899Y85283D01*
G01D02*
X610939Y84945D01*
G01D02*
X610999Y84720D01*
G01D02*
X611119Y84495D01*
G01D02*
X611259Y84345D01*
G01D02*
X611399Y84270D01*
G01D02*
X611539D01*
G01D02*
X611679Y84345D01*
G01X606173Y88280D02*
Y82328D01*
G01D02*
X617976D01*
G01X609819Y73080D02*
X610579D01*
G01X610299Y71992D02*
X609819D01*
G01X611629Y73080D02*
X611089D01*
G01X611709Y72030D02*
X611089D01*
G01X618074Y74804D02*
X606074D01*
G01X617976Y88280D02*
X606173D01*
G01X600858Y150492D02*
X601033Y152117D01*
G01D02*
X601296Y153492D01*
G01D02*
X601646Y154742D01*
G01D02*
X602083Y156117D01*
G01D02*
X602783Y157992D01*
G01D02*
X599283D01*
G01X616237Y170709D02*
X610987D01*
G01X601033Y228445D02*
X601646Y228570D01*
G01D02*
X602346Y228945D01*
G01D02*
X602783Y229570D01*
G01D02*
X602958Y230445D01*
G01D02*
X602783Y231320D01*
G01D02*
X602258Y232070D01*
G01D02*
X601471Y232445D01*
G01D02*
X600596D01*
G01D02*
X600071Y232695D01*
G01D02*
X599633Y233320D01*
G01D02*
X599458Y234195D01*
G01D02*
X599721Y235070D01*
G01D02*
X600333Y235695D01*
G01D02*
X601033Y235945D01*
G01D02*
X601733Y235695D01*
G01D02*
X602346Y235070D01*
G01D02*
X602609Y234195D01*
G01D02*
X602433Y233320D01*
G01D02*
X601996Y232695D01*
G01D02*
X601471Y232445D01*
G01D02*
X600596D01*
G01D02*
X599808Y232070D01*
G01D02*
X599283Y231320D01*
G01D02*
X599108Y230445D01*
G01D02*
X599283Y229570D01*
G01D02*
X599721Y228945D01*
G01D02*
X600421Y228570D01*
G01D02*
X601033Y228445D01*
G01X618074Y68804D02*
Y74804D01*
G01X621981Y74406D02*
Y68453D01*
G01D02*
X633817D01*
G01X611749Y70830D02*
X611889Y70980D01*
G01X613139Y70830D02*
Y73080D01*
G01X626619Y70380D02*
Y72630D01*
G01X612074Y77520D02*
Y79770D01*
G01D02*
X611834Y79320D01*
G01Y77520D02*
X612314D01*
G01X613424Y79770D02*
X613264Y79695D01*
G01D02*
X613144Y79508D01*
G01D02*
X613064Y79283D01*
G01D02*
X613004Y78983D01*
G01D02*
X612984Y78645D01*
G01D02*
X613004Y78308D01*
G01D02*
X613064Y78008D01*
G01D02*
X613144Y77783D01*
G01D02*
X613264Y77595D01*
G01D02*
X613424Y77520D01*
G01D02*
X613584Y77595D01*
G01D02*
X613704Y77783D01*
G01D02*
X613784Y78008D01*
G01D02*
X613844Y78308D01*
G01D02*
X613864Y78645D01*
G01D02*
X613844Y78983D01*
G01D02*
X613784Y79283D01*
G01D02*
X613704Y79508D01*
G01D02*
X613584Y79695D01*
G01D02*
X613424Y79770D01*
G01X617976Y75578D02*
Y81530D01*
G01X611839Y86333D02*
X611719Y86445D01*
G01X611679Y84345D02*
X611799Y84458D01*
G01D02*
X611899Y84608D01*
G01X612409Y84533D02*
X612549Y84345D01*
G01D02*
X612709Y84270D01*
G01D02*
X612869Y84345D01*
G01D02*
X613009Y84570D01*
G01D02*
X613109Y84908D01*
G01D02*
X613149Y85245D01*
G01D02*
Y85658D01*
G01D02*
X613109Y85995D01*
G01D02*
X613009Y86295D01*
G01D02*
X612889Y86445D01*
G01D02*
X612749Y86520D01*
G01D02*
X612589Y86445D01*
G01D02*
X612469Y86295D01*
G01D02*
X612389Y86070D01*
G01D02*
X612349Y85770D01*
G01D02*
X612389Y85508D01*
G01D02*
X612489Y85245D01*
G01D02*
X612609Y85095D01*
G01D02*
X612749Y85058D01*
G01D02*
X612909Y85133D01*
G01D02*
X613029Y85320D01*
G01D02*
X613149Y85658D01*
G01X617976Y82328D02*
Y88280D01*
G01X611709Y72030D02*
X611789Y72142D01*
G01D02*
X611849Y72329D01*
G01D02*
X611889Y72592D01*
G01D02*
X611849Y72817D01*
G01D02*
X611769Y72967D01*
G01D02*
X611629Y73080D01*
G01X611889Y70980D02*
X611969Y71205D01*
G01D02*
X612009Y71467D01*
G01D02*
X611969Y71729D01*
G01D02*
X611849Y71954D01*
G01D02*
X611709Y72030D01*
G01X613139Y73080D02*
X612399Y71467D01*
G01D02*
X613399D01*
G01X633817Y74406D02*
X621981D01*
G01X626619Y72630D02*
X627379D01*
G01X627099Y71542D02*
X626619D01*
G01X620108Y129213D02*
X626014Y135118D01*
G01D02*
Y174685D01*
G01X615537Y173459D02*
X611687Y167959D01*
G01X613612Y166959D02*
Y174459D01*
G01X611687Y173459D02*
X615537Y167959D01*
G01X633817Y68453D02*
Y74406D01*
G01X627929Y70679D02*
X628089Y70492D01*
G01D02*
X628269Y70380D01*
G01D02*
X628429D01*
G01D02*
X628589Y70492D01*
G01D02*
X628709Y70679D01*
G01D02*
X628769Y70942D01*
G01X629939Y70380D02*
Y72630D01*
G01X628769Y70942D02*
X628729Y71204D01*
G01D02*
X628629Y71430D01*
G01D02*
X628449Y71580D01*
G01D02*
X628209Y71655D01*
G01D02*
X628069Y71804D01*
G01D02*
X628009Y72067D01*
G01D02*
X628049Y72330D01*
G01D02*
X628149Y72517D01*
G01D02*
X628289Y72630D01*
G01D02*
X628429D01*
G01D02*
X628569Y72555D01*
G01D02*
X628689Y72367D01*
G01X629939Y72630D02*
X629199Y71017D01*
G01D02*
X630199D01*
G01X641368Y114626D02*
Y402343D01*
G01X654451Y48425D02*
X669510D01*
G01X654451Y187973D02*
Y48425D01*
G01X717344Y187973D02*
X654451D01*
G01X669510Y-128149D02*
X702285D01*
G01X669510Y48425D02*
Y-128149D01*
G01X668945Y264844D02*
X668833Y264724D01*
G01D02*
X668758Y264584D01*
G01D02*
Y264424D01*
G01D02*
X668870Y264244D01*
G01D02*
X669058Y264104D01*
G01D02*
X669283Y264004D01*
G01D02*
X669658Y263924D01*
G01D02*
X669995Y263904D01*
G01D02*
X670333Y263944D01*
G01D02*
X670558Y264004D01*
G01D02*
X670783Y264124D01*
G01D02*
X670933Y264264D01*
G01D02*
X671008Y264404D01*
G01D02*
Y264544D01*
G01D02*
X670933Y264684D01*
G01D02*
X670820Y264804D01*
G01D02*
X670670Y264904D01*
G01X671008Y265754D02*
X668758D01*
G01D02*
X669208Y265514D01*
G01X671008D02*
Y265994D01*
G01Y267104D02*
X670970Y267244D01*
G01D02*
X670858Y267404D01*
G01D02*
X670670Y267504D01*
G01D02*
X670408Y267544D01*
G01D02*
X670145Y267504D01*
G01D02*
X669920Y267384D01*
G01D02*
X669808Y267204D01*
G01D02*
Y267004D01*
G01D02*
X669733Y266884D01*
G01D02*
X669545Y266784D01*
G01D02*
X669283Y266744D01*
G01D02*
X669020Y266804D01*
G01D02*
X668833Y266944D01*
G01D02*
X668758Y267104D01*
G01D02*
X668833Y267264D01*
G01D02*
X669020Y267404D01*
G01D02*
X669283Y267464D01*
G01D02*
X669545Y267424D01*
G01D02*
X669733Y267324D01*
G01D02*
X669808Y267204D01*
G01D02*
Y267004D01*
G01D02*
X669920Y266824D01*
G01D02*
X670145Y266704D01*
G01D02*
X670408Y266664D01*
G01D02*
X670670Y266704D01*
G01D02*
X670858Y266804D01*
G01D02*
X670970Y266964D01*
G01D02*
X671008Y267104D01*
G01X666998Y259853D02*
X672951D01*
G01X666998Y271655D02*
Y259853D01*
G01X672951Y271655D02*
X666998D01*
G01X673748Y259853D02*
X679701D01*
G01X673748Y271655D02*
Y259853D01*
G01X679701Y271655D02*
X673748D01*
G01X672951Y259853D02*
Y271655D01*
G01X667598Y278453D02*
Y296555D01*
G01X678351Y278453D02*
X667598D01*
G01X671526Y286594D02*
X671414Y286474D01*
G01D02*
X671339Y286334D01*
G01D02*
Y286174D01*
G01D02*
X671451Y285994D01*
G01D02*
X671639Y285854D01*
G01D02*
X671864Y285754D01*
G01D02*
X672239Y285674D01*
G01D02*
X672576Y285654D01*
G01D02*
X672914Y285694D01*
G01D02*
X673139Y285754D01*
G01D02*
X673364Y285874D01*
G01D02*
X673514Y286014D01*
G01D02*
X673589Y286154D01*
G01D02*
Y286294D01*
G01D02*
X673514Y286434D01*
G01D02*
X673401Y286554D01*
G01D02*
X673251Y286654D01*
G01X671714Y287124D02*
X671489Y287244D01*
G01D02*
X671376Y287384D01*
G01D02*
X671339Y287544D01*
G01D02*
X671414Y287744D01*
G01D02*
X671601Y287884D01*
G01D02*
X671826Y287924D01*
G01D02*
X672051Y287904D01*
G01D02*
X672239Y287824D01*
G01D02*
X672614Y287424D01*
G01D02*
X672876Y287244D01*
G01D02*
X673251Y287124D01*
G01D02*
X673589Y287084D01*
G01D02*
Y287924D01*
G01X673251Y288414D02*
X673439Y288534D01*
G01D02*
X673551Y288674D01*
G01D02*
X673589Y288854D01*
G01D02*
X673514Y289034D01*
G01D02*
X673364Y289174D01*
G01D02*
X673101Y289274D01*
G01D02*
X672801Y289294D01*
G01D02*
X672501Y289254D01*
G01D02*
X672314Y289154D01*
G01D02*
X672164Y289014D01*
G01D02*
X672126Y288874D01*
G01D02*
X672164Y288734D01*
G01D02*
X672314Y288554D01*
G01D02*
X671339Y288614D01*
G01D02*
Y289154D01*
G01X678351Y298703D02*
X667598D01*
G01D02*
Y316805D01*
G01Y296555D02*
X678351D01*
G01X671798Y306844D02*
X671685Y306724D01*
G01D02*
X671610Y306584D01*
G01D02*
Y306424D01*
G01D02*
X671723Y306244D01*
G01D02*
X671910Y306104D01*
G01D02*
X672135Y306004D01*
G01D02*
X672510Y305924D01*
G01D02*
X672848Y305904D01*
G01D02*
X673185Y305944D01*
G01D02*
X673410Y306004D01*
G01D02*
X673635Y306124D01*
G01D02*
X673785Y306264D01*
G01D02*
X673860Y306404D01*
G01D02*
Y306544D01*
G01D02*
X673785Y306684D01*
G01D02*
X673673Y306804D01*
G01D02*
X673523Y306904D01*
G01X667598Y316805D02*
X678351D01*
G01X667598Y320453D02*
Y338555D01*
G01X678351Y320453D02*
X667598D01*
G01X671985Y307374D02*
X671760Y307494D01*
G01D02*
X671648Y307634D01*
G01D02*
X671610Y307794D01*
G01D02*
X671685Y307994D01*
G01D02*
X671873Y308134D01*
G01D02*
X672098Y308174D01*
G01D02*
X672323Y308154D01*
G01D02*
X672510Y308074D01*
G01D02*
X672885Y307674D01*
G01D02*
X673148Y307494D01*
G01D02*
X673523Y307374D01*
G01D02*
X673860Y307334D01*
G01D02*
Y308174D01*
G01X673410Y308664D02*
X673673Y308784D01*
G01D02*
X673823Y308944D01*
G01D02*
X673860Y309124D01*
G01D02*
X673823Y309284D01*
G01D02*
X673635Y309444D01*
G01D02*
X673410Y309544D01*
G01D02*
X673185Y309564D01*
G01D02*
X672923Y309524D01*
G01D02*
X672735Y309384D01*
G01D02*
X672660Y309244D01*
G01D02*
Y309064D01*
G01Y309244D02*
X672548Y309364D01*
G01D02*
X672360Y309464D01*
G01D02*
X672135Y309504D01*
G01D02*
X671910Y309464D01*
G01D02*
X671723Y309364D01*
G01D02*
X671610Y309184D01*
G01D02*
X671648Y309004D01*
G01D02*
X671798Y308824D01*
G01X667598Y338555D02*
X678351D01*
G01X671526Y328594D02*
X671414Y328474D01*
G01D02*
X671339Y328334D01*
G01D02*
Y328174D01*
G01D02*
X671451Y327994D01*
G01D02*
X671639Y327854D01*
G01D02*
X671864Y327754D01*
G01D02*
X672239Y327674D01*
G01D02*
X672576Y327654D01*
G01D02*
X672914Y327694D01*
G01D02*
X673139Y327754D01*
G01D02*
X673364Y327874D01*
G01D02*
X673514Y328014D01*
G01D02*
X673589Y328154D01*
G01D02*
Y328294D01*
G01D02*
X673514Y328434D01*
G01D02*
X673401Y328554D01*
G01D02*
X673251Y328654D01*
G01X671714Y329124D02*
X671489Y329244D01*
G01D02*
X671376Y329384D01*
G01D02*
X671339Y329544D01*
G01D02*
X671414Y329744D01*
G01D02*
X671601Y329884D01*
G01D02*
X671826Y329924D01*
G01D02*
X672051Y329904D01*
G01D02*
X672239Y329824D01*
G01D02*
X672614Y329424D01*
G01D02*
X672876Y329244D01*
G01D02*
X673251Y329124D01*
G01D02*
X673589Y329084D01*
G01D02*
Y329924D01*
G01X672651Y330474D02*
X672389Y330614D01*
G01D02*
X672239Y330734D01*
G01D02*
X672164Y330894D01*
G01D02*
X672239Y331034D01*
G01D02*
X672389Y331134D01*
G01D02*
X672614Y331214D01*
G01D02*
X672876Y331234D01*
G01D02*
X673101Y331214D01*
G01D02*
X673326Y331134D01*
G01D02*
X673514Y331014D01*
G01D02*
X673589Y330874D01*
G01D02*
X673514Y330714D01*
G01D02*
X673289Y330574D01*
G01D02*
X672951Y330494D01*
G01D02*
X672576Y330474D01*
G01D02*
X672089Y330514D01*
G01D02*
X671826Y330574D01*
G01D02*
X671564Y330674D01*
G01D02*
X671376Y330814D01*
G01D02*
X671339Y330954D01*
G01D02*
X671414Y331094D01*
G01D02*
X671601Y331194D01*
G01X678575Y341228D02*
X667822D01*
G01D02*
Y359331D01*
G01X672022Y349370D02*
X671910Y349250D01*
G01D02*
X671835Y349110D01*
G01D02*
Y348950D01*
G01D02*
X671947Y348770D01*
G01D02*
X672135Y348630D01*
G01D02*
X672360Y348530D01*
G01D02*
X672735Y348450D01*
G01D02*
X673072Y348430D01*
G01D02*
X673410Y348470D01*
G01D02*
X673635Y348530D01*
G01D02*
X673860Y348650D01*
G01D02*
X674010Y348790D01*
G01D02*
X674085Y348930D01*
G01D02*
Y349070D01*
G01D02*
X674010Y349210D01*
G01D02*
X673897Y349330D01*
G01D02*
X673747Y349430D01*
G01X672210Y349900D02*
X671985Y350020D01*
G01D02*
X671872Y350160D01*
G01D02*
X671835Y350320D01*
G01D02*
X671910Y350520D01*
G01D02*
X672097Y350660D01*
G01D02*
X672322Y350700D01*
G01D02*
X672547Y350680D01*
G01D02*
X672735Y350600D01*
G01D02*
X673110Y350200D01*
G01D02*
X673372Y350020D01*
G01D02*
X673747Y349900D01*
G01D02*
X674085Y349860D01*
G01D02*
Y350700D01*
G01Y351870D02*
X671835D01*
G01D02*
X673447Y351130D01*
G01D02*
Y352130D01*
G01X667822Y359331D02*
X678575D01*
G01X687822Y126982D02*
X683972Y121482D01*
G01X685898Y120482D02*
Y127982D01*
G01X683972Y126982D02*
X687822Y121482D01*
G01X688522Y124232D02*
X683272D01*
G01X677803Y168784D02*
X678241Y168034D01*
G01D02*
X678766Y167534D01*
G01D02*
X679378Y167284D01*
G01D02*
X680078Y167534D01*
G01D02*
X680603Y168034D01*
G01D02*
X681128Y168784D01*
G01D02*
X681303Y169784D01*
G01D02*
Y174784D01*
G01X685391Y173534D02*
X685916Y174284D01*
G01D02*
X686528Y174659D01*
G01D02*
X687228Y174784D01*
G01D02*
X688103Y174534D01*
G01D02*
X688716Y173909D01*
G01D02*
X688891Y173159D01*
G01D02*
X688803Y172409D01*
G01D02*
X688453Y171784D01*
G01D02*
X686703Y170534D01*
G01D02*
X685916Y169659D01*
G01D02*
X685391Y168409D01*
G01D02*
X685216Y167284D01*
G01D02*
X688891D01*
G01X681309Y258878D02*
Y266630D01*
G01X696139Y258878D02*
X681309D01*
G01X675695Y264844D02*
X675583Y264724D01*
G01D02*
X675508Y264584D01*
G01D02*
Y264424D01*
G01D02*
X675620Y264244D01*
G01D02*
X675808Y264104D01*
G01D02*
X676033Y264004D01*
G01D02*
X676408Y263924D01*
G01D02*
X676745Y263904D01*
G01D02*
X677083Y263944D01*
G01D02*
X677308Y264004D01*
G01D02*
X677533Y264124D01*
G01D02*
X677683Y264264D01*
G01D02*
X677758Y264404D01*
G01D02*
Y264544D01*
G01D02*
X677683Y264684D01*
G01D02*
X677570Y264804D01*
G01D02*
X677420Y264904D01*
G01X677758Y265754D02*
X675508D01*
G01D02*
X675958Y265514D01*
G01X677758D02*
Y265994D01*
G01Y267064D02*
X677270Y267104D01*
G01D02*
X676858Y267164D01*
G01D02*
X676483Y267244D01*
G01D02*
X676070Y267344D01*
G01D02*
X675508Y267504D01*
G01D02*
Y266704D01*
G01X679701Y259853D02*
Y271655D01*
G01X685370Y271121D02*
X683120D01*
G01D02*
Y271881D01*
G01X684207Y271601D02*
Y271121D01*
G01X684170Y273011D02*
X684057Y273091D01*
G01D02*
X683870Y273151D01*
G01D02*
X683607Y273191D01*
G01D02*
X683382Y273151D01*
G01D02*
X683232Y273071D01*
G01D02*
X683120Y272931D01*
G01D02*
Y272391D01*
G01D02*
X685370D01*
G01D02*
Y273051D01*
G01D02*
X685220Y273191D01*
G01D02*
X684995Y273271D01*
G01D02*
X684732Y273311D01*
G01D02*
X684470Y273271D01*
G01D02*
X684245Y273151D01*
G01D02*
X684170Y273011D01*
G01D02*
Y272391D01*
G01X685370Y274161D02*
X684882Y274201D01*
G01D02*
X684470Y274261D01*
G01D02*
X684095Y274341D01*
G01D02*
X683682Y274441D01*
G01D02*
X683120Y274601D01*
G01D02*
Y273801D01*
G01X681224Y267254D02*
X687224D01*
G01X681224Y279254D02*
Y267254D01*
G01X687224D02*
Y279254D01*
G01X689498Y267336D02*
X695451D01*
G01X689498Y279172D02*
Y267336D01*
G01X686974Y261573D02*
Y263823D01*
G01D02*
X687474D01*
G01D02*
X687634Y263710D01*
G01D02*
X687734Y263560D01*
G01D02*
X687774Y263260D01*
G01D02*
X687734Y262960D01*
G01D02*
X687614Y262773D01*
G01D02*
X687474Y262660D01*
G01D02*
X686974D01*
G01X687474D02*
X687774Y261573D01*
G01X688344Y262510D02*
X688484Y262773D01*
G01D02*
X688604Y262923D01*
G01D02*
X688764Y262998D01*
G01D02*
X688904Y262923D01*
G01D02*
X689004Y262773D01*
G01D02*
X689084Y262548D01*
G01D02*
X689104Y262285D01*
G01D02*
X689084Y262060D01*
G01D02*
X689004Y261835D01*
G01D02*
X688884Y261648D01*
G01D02*
X688744Y261573D01*
G01D02*
X688584Y261648D01*
G01D02*
X688444Y261873D01*
G01D02*
X688364Y262210D01*
G01D02*
X688344Y262585D01*
G01D02*
X688384Y263073D01*
G01D02*
X688444Y263335D01*
G01D02*
X688544Y263598D01*
G01D02*
X688684Y263785D01*
G01D02*
X688824Y263823D01*
G01D02*
X688964Y263748D01*
G01D02*
X689064Y263560D01*
G01X690074Y263823D02*
X689914Y263748D01*
G01D02*
X689794Y263560D01*
G01D02*
X689714Y263335D01*
G01D02*
X689654Y263035D01*
G01D02*
X689634Y262698D01*
G01D02*
X689654Y262360D01*
G01D02*
X689714Y262060D01*
G01D02*
X689794Y261835D01*
G01D02*
X689914Y261648D01*
G01D02*
X690074Y261573D01*
G01D02*
X690234Y261648D01*
G01D02*
X690354Y261835D01*
G01Y263560D02*
X690234Y263748D01*
G01D02*
X690074Y263823D01*
G01X681309Y266630D02*
X696139D01*
G01X678351Y296555D02*
Y278453D01*
G01X687224Y279254D02*
X681224D01*
G01X695451Y279172D02*
X689498D01*
G01X680886Y287120D02*
X680774Y287000D01*
G01D02*
X680699Y286860D01*
G01D02*
Y286700D01*
G01D02*
X680811Y286520D01*
G01D02*
X680999Y286380D01*
G01D02*
X681224Y286280D01*
G01D02*
X681599Y286200D01*
G01D02*
X681936Y286180D01*
G01D02*
X682274Y286220D01*
G01D02*
X682499Y286280D01*
G01D02*
X682724Y286400D01*
G01D02*
X682874Y286540D01*
G01D02*
X682949Y286680D01*
G01D02*
Y286820D01*
G01D02*
X682874Y286960D01*
G01D02*
X682761Y287080D01*
G01D02*
X682611Y287180D01*
G01X682949Y288030D02*
X680699D01*
G01D02*
X681149Y287790D01*
G01X682949D02*
Y288270D01*
G01X682686Y289040D02*
X682874Y289180D01*
G01D02*
X682949Y289340D01*
G01D02*
X682874Y289500D01*
G01D02*
X682649Y289640D01*
G01D02*
X682311Y289740D01*
G01D02*
X681974Y289780D01*
G01D02*
X681561D01*
G01D02*
X681224Y289740D01*
G01D02*
X680924Y289640D01*
G01D02*
X680774Y289520D01*
G01D02*
X680699Y289380D01*
G01D02*
X680774Y289220D01*
G01D02*
X680924Y289100D01*
G01D02*
X681149Y289020D01*
G01D02*
X681449Y288980D01*
G01D02*
X681711Y289020D01*
G01D02*
X681974Y289120D01*
G01D02*
X682124Y289240D01*
G01D02*
X682161Y289380D01*
G01D02*
X682086Y289540D01*
G01D02*
X681899Y289660D01*
G01D02*
X681561Y289780D01*
G01X684951Y282353D02*
Y294155D01*
G01X678998Y282353D02*
X684951D01*
G01X678998Y294155D02*
Y282353D01*
G01X686184Y287198D02*
Y294951D01*
G01X701014Y287198D02*
X686184D01*
G01X684951Y294155D02*
X678998D01*
G01X680945Y306844D02*
X680833Y306724D01*
G01D02*
X680758Y306584D01*
G01D02*
Y306424D01*
G01D02*
X680870Y306244D01*
G01D02*
X681058Y306104D01*
G01D02*
X681283Y306004D01*
G01D02*
X681658Y305924D01*
G01D02*
X681995Y305904D01*
G01D02*
X682333Y305944D01*
G01D02*
X682558Y306004D01*
G01D02*
X682783Y306124D01*
G01D02*
X682933Y306264D01*
G01D02*
X683008Y306404D01*
G01D02*
Y306544D01*
G01D02*
X682933Y306684D01*
G01D02*
X682820Y306804D01*
G01D02*
X682670Y306904D01*
G01X678998Y301853D02*
X684951D01*
G01X678998Y313655D02*
Y301853D01*
G01X684951D02*
Y313655D01*
G01X678351Y316805D02*
Y298703D01*
G01X689469Y297030D02*
Y299280D01*
G01D02*
X690229D01*
G01X689949Y298192D02*
X689469D01*
G01X684974Y295004D02*
X696974D01*
G01X684974Y301004D02*
Y295004D01*
G01X696974Y301004D02*
X684974D01*
G01X689769Y304680D02*
Y306930D01*
G01D02*
X690529D01*
G01X690249Y305842D02*
X689769D01*
G01X684981Y309006D02*
Y303053D01*
G01D02*
X696817D01*
G01X686184Y294951D02*
X701014D01*
G01X681133Y307374D02*
X680908Y307494D01*
G01D02*
X680795Y307634D01*
G01D02*
X680758Y307794D01*
G01D02*
X680833Y307994D01*
G01D02*
X681020Y308134D01*
G01D02*
X681245Y308174D01*
G01D02*
X681470Y308154D01*
G01D02*
X681658Y308074D01*
G01D02*
X682033Y307674D01*
G01D02*
X682295Y307494D01*
G01D02*
X682670Y307374D01*
G01D02*
X683008Y307334D01*
G01D02*
Y308174D01*
G01Y309104D02*
X680758D01*
G01D02*
X681208Y308864D01*
G01X683008D02*
Y309344D01*
G01X684951Y313655D02*
X678998D01*
G01X678351Y338555D02*
Y320453D01*
G01X690436Y321118D02*
X690276D01*
G01D02*
X690096Y321006D01*
G01D02*
X689956Y320818D01*
G01D02*
X689856Y320593D01*
G01D02*
X689776Y320218D01*
G01D02*
X689756Y319881D01*
G01D02*
X689796Y319543D01*
G01D02*
X689856Y319318D01*
G01D02*
X689976Y319093D01*
G01D02*
X690116Y318943D01*
G01D02*
X690256Y318868D01*
G01D02*
X690396D01*
G01X682555Y314378D02*
Y325130D01*
G01X700658Y314378D02*
X682555D01*
G01X696817Y309006D02*
X684981D01*
G01X684951Y325853D02*
Y337655D01*
G01X678998Y325853D02*
X684951D01*
G01X678998Y337655D02*
Y325853D01*
G01X682555Y325130D02*
X700658D01*
G01X686034Y329153D02*
Y336906D01*
G01X700864Y329153D02*
X686034D01*
G01X680378Y330844D02*
X680266Y330724D01*
G01D02*
X680191Y330584D01*
G01D02*
Y330424D01*
G01D02*
X680303Y330244D01*
G01D02*
X680491Y330104D01*
G01D02*
X680716Y330004D01*
G01D02*
X681091Y329924D01*
G01D02*
X681428Y329904D01*
G01D02*
X681766Y329944D01*
G01D02*
X681991Y330004D01*
G01D02*
X682216Y330124D01*
G01D02*
X682366Y330264D01*
G01D02*
X682441Y330404D01*
G01D02*
Y330544D01*
G01D02*
X682366Y330684D01*
G01D02*
X682253Y330804D01*
G01D02*
X682104Y330904D01*
G01X680566Y331374D02*
X680341Y331494D01*
G01D02*
X680228Y331634D01*
G01D02*
X680191Y331794D01*
G01D02*
X680266Y331994D01*
G01D02*
X680453Y332134D01*
G01D02*
X680678Y332174D01*
G01D02*
X680903Y332154D01*
G01D02*
X681091Y332074D01*
G01D02*
X681466Y331674D01*
G01D02*
X681728Y331494D01*
G01D02*
X682104Y331374D01*
G01D02*
X682441Y331334D01*
G01D02*
Y332174D01*
G01X680191Y333104D02*
X680266Y332944D01*
G01D02*
X680453Y332824D01*
G01D02*
X680678Y332744D01*
G01D02*
X680978Y332684D01*
G01D02*
X681316Y332664D01*
G01D02*
X681653Y332684D01*
G01D02*
X681953Y332744D01*
G01D02*
X682178Y332824D01*
G01D02*
X682366Y332944D01*
G01D02*
X682441Y333104D01*
G01D02*
X682366Y333264D01*
G01D02*
X682178Y333384D01*
G01D02*
X681953Y333464D01*
G01D02*
X681653Y333524D01*
G01D02*
X681316Y333544D01*
G01D02*
X680978Y333524D01*
G01D02*
X680678Y333464D01*
G01D02*
X680453Y333384D01*
G01D02*
X680266Y333264D01*
G01D02*
X680191Y333104D01*
G01X684951Y337655D02*
X678998D01*
G01X686699Y338280D02*
X698699D01*
G01X686699Y344280D02*
Y338280D01*
G01X686034Y336906D02*
X700864D01*
G01X680945Y345844D02*
X680833Y345724D01*
G01D02*
X680758Y345584D01*
G01D02*
Y345424D01*
G01D02*
X680870Y345244D01*
G01D02*
X681058Y345104D01*
G01D02*
X681283Y345004D01*
G01D02*
X681658Y344924D01*
G01D02*
X681995Y344904D01*
G01D02*
X682333Y344944D01*
G01D02*
X682558Y345004D01*
G01D02*
X682783Y345124D01*
G01D02*
X682933Y345264D01*
G01D02*
X683008Y345404D01*
G01D02*
Y345544D01*
G01D02*
X682933Y345684D01*
G01D02*
X682820Y345804D01*
G01D02*
X682670Y345904D01*
G01X681133Y346374D02*
X680908Y346494D01*
G01D02*
X680795Y346634D01*
G01D02*
X680758Y346794D01*
G01D02*
X680833Y346994D01*
G01D02*
X681020Y347134D01*
G01D02*
X681245Y347174D01*
G01D02*
X681470Y347154D01*
G01D02*
X681658Y347074D01*
G01D02*
X682033Y346674D01*
G01D02*
X682295Y346494D01*
G01D02*
X682670Y346374D01*
G01D02*
X683008Y346334D01*
G01D02*
Y347174D01*
G01X681133Y347724D02*
X680908Y347844D01*
G01D02*
X680795Y347984D01*
G01D02*
X680758Y348144D01*
G01D02*
X680833Y348344D01*
G01D02*
X681020Y348484D01*
G01D02*
X681245Y348524D01*
G01D02*
X681470Y348504D01*
G01D02*
X681658Y348424D01*
G01D02*
X682033Y348024D01*
G01D02*
X682295Y347844D01*
G01D02*
X682670Y347724D01*
G01D02*
X683008Y347684D01*
G01D02*
Y348524D01*
G01X678998Y340853D02*
X684951D01*
G01X678998Y352655D02*
Y340853D01*
G01X684951Y352655D02*
X678998D01*
G01X684951Y340853D02*
Y352655D01*
G01X678575Y359331D02*
Y341228D01*
G01X698699Y344280D02*
X686699D01*
G01X686781Y352506D02*
Y346553D01*
G01X698617Y352506D02*
X686781D01*
G01Y346553D02*
X698617D01*
G01X702285Y-128149D02*
Y48425D01*
G01D02*
X717344D01*
G01X692891Y173534D02*
X693416Y174284D01*
G01D02*
X694028Y174659D01*
G01D02*
X694728Y174784D01*
G01D02*
X695603Y174534D01*
G01D02*
X696216Y173909D01*
G01D02*
X696391Y173159D01*
G01D02*
X696303Y172409D01*
G01D02*
X695953Y171784D01*
G01D02*
X694203Y170534D01*
G01D02*
X693416Y169659D01*
G01D02*
X692891Y168409D01*
G01D02*
X692716Y167284D01*
G01D02*
X696391D01*
G01X696139Y266630D02*
Y258878D01*
G01X693717Y271261D02*
X691467D01*
G01D02*
Y272021D01*
G01X692554Y271741D02*
Y271261D01*
G01X693417Y272571D02*
X693604Y272731D01*
G01D02*
X693717Y272911D01*
G01D02*
Y273071D01*
G01D02*
X693604Y273231D01*
G01D02*
X693417Y273351D01*
G01D02*
X693154Y273411D01*
G01D02*
X692892Y273371D01*
G01D02*
X692667Y273271D01*
G01D02*
X692517Y273091D01*
G01D02*
X692442Y272851D01*
G01D02*
X692292Y272711D01*
G01D02*
X692029Y272651D01*
G01D02*
X691767Y272691D01*
G01D02*
X691580Y272791D01*
G01D02*
X691467Y272931D01*
G01D02*
Y273071D01*
G01D02*
X691542Y273211D01*
G01D02*
X691729Y273331D01*
G01X693717Y274301D02*
X693229Y274341D01*
G01D02*
X692817Y274401D01*
G01D02*
X692442Y274481D01*
G01D02*
X692029Y274581D01*
G01D02*
X691467Y274741D01*
G01D02*
Y273941D01*
G01X690354Y261835D02*
X690434Y262060D01*
G01D02*
X690494Y262360D01*
G01D02*
X690514Y262698D01*
G01D02*
X690494Y263035D01*
G01D02*
X690434Y263335D01*
G01D02*
X690354Y263560D01*
G01X695451Y267336D02*
Y279172D01*
G01X691699Y289530D02*
Y291780D01*
G01X692459Y291517D02*
X692499Y291217D01*
G01D02*
X692459Y290917D01*
G01D02*
X692339Y290730D01*
G01D02*
X692199Y290617D01*
G01D02*
X691699D01*
G01X692199D02*
X692499Y289530D01*
G01X693009Y289867D02*
X693129Y289680D01*
G01D02*
X693269Y289567D01*
G01D02*
X693449Y289530D01*
G01D02*
X693629Y289605D01*
G01D02*
X693769Y289754D01*
G01D02*
X693869Y290017D01*
G01D02*
X693889Y290317D01*
G01D02*
X693849Y290617D01*
G01D02*
X693749Y290805D01*
G01D02*
X693609Y290954D01*
G01D02*
X693469Y290992D01*
G01D02*
X693329Y290954D01*
G01D02*
X693149Y290805D01*
G01D02*
X693209Y291780D01*
G01X694799Y289530D02*
X694939Y289567D01*
G01D02*
X695099Y289680D01*
G01D02*
X695199Y289867D01*
G01D02*
X695239Y290130D01*
G01D02*
X695199Y290392D01*
G01D02*
X695079Y290617D01*
G01D02*
X694899Y290730D01*
G01D02*
X694699D01*
G01D02*
X694579Y290805D01*
G01D02*
X694479Y290992D01*
G01D02*
X694439Y291254D01*
G01D02*
X694499Y291517D01*
G01X695099D02*
X695159Y291254D01*
G01D02*
X695119Y290992D01*
G01D02*
X695019Y290805D01*
G01D02*
X694899Y290730D01*
G01D02*
X694699D01*
G01D02*
X694519Y290617D01*
G01D02*
X694399Y290392D01*
G01D02*
X694359Y290130D01*
G01D02*
X694399Y289867D01*
G01D02*
X694499Y289680D01*
G01D02*
X694659Y289567D01*
G01D02*
X694799Y289530D01*
G01X701014Y294951D02*
Y287198D01*
G01X691359Y298230D02*
X691439Y298342D01*
G01D02*
X691499Y298529D01*
G01D02*
X691539Y298792D01*
G01D02*
X691499Y299017D01*
G01D02*
X691419Y299167D01*
G01D02*
X691279Y299280D01*
G01D02*
X690739D01*
G01D02*
Y297030D01*
G01D02*
X691399D01*
G01D02*
X691539Y297180D01*
G01D02*
X691619Y297405D01*
G01D02*
X691659Y297667D01*
G01D02*
X691619Y297929D01*
G01D02*
X691499Y298154D01*
G01D02*
X691359Y298230D01*
G01D02*
X690739D01*
G01X692109Y297367D02*
X692229Y297180D01*
G01D02*
X692369Y297067D01*
G01D02*
X692549Y297030D01*
G01D02*
X692729Y297105D01*
G01D02*
X692869Y297254D01*
G01D02*
X692969Y297517D01*
G01D02*
X692989Y297817D01*
G01D02*
X692949Y298117D01*
G01D02*
X692849Y298305D01*
G01D02*
X692709Y298454D01*
G01D02*
X692569Y298492D01*
G01D02*
X692429Y298454D01*
G01D02*
X692249Y298305D01*
G01D02*
X692309Y299280D01*
G01D02*
X692849D01*
G01X691079Y304979D02*
X691239Y304792D01*
G01D02*
X691419Y304680D01*
G01D02*
X691579D01*
G01D02*
X691739Y304792D01*
G01D02*
X691859Y304979D01*
G01D02*
X691919Y305242D01*
G01D02*
X691879Y305504D01*
G01D02*
X691779Y305730D01*
G01D02*
X691599Y305880D01*
G01D02*
X691359Y305955D01*
G01D02*
X691219Y306104D01*
G01D02*
X691159Y306367D01*
G01D02*
X691199Y306630D01*
G01D02*
X691299Y306817D01*
G01D02*
X691439Y306930D01*
G01D02*
X691579D01*
G01D02*
X691719Y306855D01*
G01D02*
X691839Y306667D01*
G01X692409Y305017D02*
X692529Y304830D01*
G01D02*
X692669Y304717D01*
G01D02*
X692849Y304680D01*
G01D02*
X693029Y304755D01*
G01D02*
X693169Y304904D01*
G01D02*
X693269Y305167D01*
G01D02*
X693289Y305467D01*
G01D02*
X693249Y305767D01*
G01D02*
X693149Y305955D01*
G01D02*
X693009Y306104D01*
G01D02*
X692869Y306142D01*
G01D02*
X692729Y306104D01*
G01D02*
X692549Y305955D01*
G01D02*
X692609Y306930D01*
G01D02*
X693149D01*
G01X691699Y291780D02*
X692199D01*
G01D02*
X692359Y291667D01*
G01D02*
X692459Y291517D01*
G01X693209Y291780D02*
X693749D01*
G01X694499Y291517D02*
X694639Y291705D01*
G01D02*
X694799Y291780D01*
G01D02*
X694959Y291705D01*
G01D02*
X695099Y291517D01*
G01X696974Y295004D02*
Y301004D01*
G01X696817Y303053D02*
Y309006D01*
G01X690696Y320931D02*
X690576Y321043D01*
G01D02*
X690436Y321118D01*
G01X690396Y318868D02*
X690536Y318943D01*
G01D02*
X690656Y319056D01*
G01D02*
X690756Y319206D01*
G01X691226Y320743D02*
X691346Y320968D01*
G01D02*
X691486Y321081D01*
G01D02*
X691646Y321118D01*
G01D02*
X691846Y321043D01*
G01D02*
X691986Y320856D01*
G01D02*
X692026Y320631D01*
G01D02*
X692006Y320406D01*
G01D02*
X691926Y320218D01*
G01D02*
X691526Y319843D01*
G01D02*
X691346Y319581D01*
G01D02*
X691226Y319206D01*
G01D02*
X691186Y318868D01*
G01D02*
X692026D01*
G01X692956D02*
X693096Y318906D01*
G01D02*
X693256Y319018D01*
G01D02*
X693356Y319206D01*
G01D02*
X693396Y319468D01*
G01D02*
X693356Y319731D01*
G01D02*
X693236Y319956D01*
G01D02*
X693056Y320068D01*
G01D02*
X692856D01*
G01D02*
X692736Y320143D01*
G01D02*
X692636Y320331D01*
G01D02*
X692596Y320593D01*
G01D02*
X692656Y320856D01*
G01D02*
X692796Y321043D01*
G01D02*
X692956Y321118D01*
G01D02*
X693116Y321043D01*
G01D02*
X693256Y320856D01*
G01D02*
X693316Y320593D01*
G01D02*
X693276Y320331D01*
G01D02*
X693176Y320143D01*
G01D02*
X693056Y320068D01*
G01D02*
X692856D01*
G01D02*
X692676Y319956D01*
G01D02*
X692556Y319731D01*
G01D02*
X692516Y319468D01*
G01D02*
X692556Y319206D01*
G01D02*
X692656Y319018D01*
G01D02*
X692816Y318906D01*
G01D02*
X692956Y318868D01*
G01X700658Y325130D02*
Y314378D01*
G01X691699Y332711D02*
Y334961D01*
G01D02*
X692199D01*
G01D02*
X692359Y334848D01*
G01D02*
X692459Y334698D01*
G01D02*
X692499Y334398D01*
G01D02*
X692459Y334098D01*
G01D02*
X692339Y333911D01*
G01D02*
X692199Y333798D01*
G01D02*
X691699D01*
G01X692199D02*
X692499Y332711D01*
G01X693009Y333048D02*
X693129Y332861D01*
G01D02*
X693269Y332748D01*
G01D02*
X693449Y332711D01*
G01D02*
X693629Y332786D01*
G01D02*
X693769Y332936D01*
G01D02*
X693869Y333198D01*
G01D02*
X693889Y333498D01*
G01D02*
X693849Y333798D01*
G01D02*
X693749Y333986D01*
G01D02*
X693609Y334136D01*
G01D02*
X693469Y334173D01*
G01D02*
X693329Y334136D01*
G01D02*
X693149Y333986D01*
G01D02*
X693209Y334961D01*
G01D02*
X693749D01*
G01X694459Y332973D02*
X694599Y332786D01*
G01D02*
X694759Y332711D01*
G01D02*
X694919Y332786D01*
G01D02*
X695059Y333011D01*
G01D02*
X695159Y333348D01*
G01D02*
X695199Y333686D01*
G01D02*
Y334098D01*
G01D02*
X695159Y334436D01*
G01D02*
X695059Y334736D01*
G01D02*
X694939Y334886D01*
G01D02*
X694799Y334961D01*
G01D02*
X694639Y334886D01*
G01D02*
X694519Y334736D01*
G01D02*
X694439Y334511D01*
G01D02*
X694399Y334211D01*
G01D02*
X694439Y333948D01*
G01D02*
X694539Y333686D01*
G01D02*
X694659Y333536D01*
G01D02*
X694799Y333498D01*
G01D02*
X694959Y333573D01*
G01D02*
X695079Y333761D01*
G01D02*
X695199Y334098D01*
G01X700864Y336906D02*
Y329153D01*
G01X698699Y338280D02*
Y344280D01*
G01X691193Y340305D02*
Y342555D01*
G01D02*
X691953D01*
G01X691673Y341468D02*
X691193D01*
G01X693083Y341505D02*
X693163Y341618D01*
G01D02*
X693223Y341805D01*
G01D02*
X693263Y342068D01*
G01D02*
X693223Y342293D01*
G01D02*
X693143Y342443D01*
G01D02*
X693003Y342555D01*
G01D02*
X692463D01*
G01D02*
Y340305D01*
G01D02*
X693123D01*
G01D02*
X693263Y340455D01*
G01D02*
X693343Y340680D01*
G01D02*
X693383Y340943D01*
G01D02*
X693343Y341205D01*
G01D02*
X693223Y341430D01*
G01D02*
X693083Y341505D01*
G01D02*
X692463D01*
G01X693893Y341243D02*
X694033Y341505D01*
G01D02*
X694153Y341655D01*
G01D02*
X694313Y341730D01*
G01D02*
X694453Y341655D01*
G01D02*
X694553Y341505D01*
G01D02*
X694633Y341280D01*
G01D02*
X694653Y341018D01*
G01D02*
X694633Y340793D01*
G01D02*
X694553Y340568D01*
G01D02*
X694433Y340380D01*
G01D02*
X694293Y340305D01*
G01D02*
X694133Y340380D01*
G01D02*
X693993Y340605D01*
G01D02*
X693913Y340943D01*
G01D02*
X693893Y341318D01*
G01D02*
X693933Y341805D01*
G01D02*
X693993Y342068D01*
G01D02*
X694093Y342330D01*
G01D02*
X694233Y342518D01*
G01D02*
X694373Y342555D01*
G01D02*
X694513Y342480D01*
G01D02*
X694613Y342293D01*
G01X691119Y348180D02*
Y350430D01*
G01D02*
X691879D01*
G01X691599Y349342D02*
X691119D01*
G01X692429Y348479D02*
X692589Y348292D01*
G01D02*
X692769Y348180D01*
G01D02*
X692929D01*
G01D02*
X693089Y348292D01*
G01D02*
X693209Y348479D01*
G01D02*
X693269Y348742D01*
G01D02*
X693229Y349004D01*
G01D02*
X693129Y349230D01*
G01D02*
X692949Y349380D01*
G01D02*
X692709Y349455D01*
G01D02*
X692569Y349604D01*
G01D02*
X692509Y349867D01*
G01D02*
X692549Y350130D01*
G01D02*
X692649Y350317D01*
G01D02*
X692789Y350430D01*
G01D02*
X692929D01*
G01D02*
X693069Y350355D01*
G01D02*
X693189Y350167D01*
G01X693819Y349117D02*
X693959Y349380D01*
G01D02*
X694079Y349530D01*
G01D02*
X694239Y349604D01*
G01D02*
X694379Y349530D01*
G01D02*
X694479Y349380D01*
G01D02*
X694559Y349155D01*
G01D02*
X694579Y348892D01*
G01D02*
X694559Y348667D01*
G01D02*
X694479Y348442D01*
G01D02*
X694359Y348255D01*
G01D02*
X694219Y348180D01*
G01D02*
X694059Y348255D01*
G01D02*
X693919Y348479D01*
G01D02*
X693839Y348817D01*
G01D02*
X693819Y349192D01*
G01D02*
X693859Y349679D01*
G01D02*
X693919Y349942D01*
G01D02*
X694019Y350205D01*
G01D02*
X694159Y350392D01*
G01D02*
X694299Y350430D01*
G01D02*
X694439Y350355D01*
G01D02*
X694539Y350167D01*
G01X698617Y346553D02*
Y352506D01*
G01X717344Y48425D02*
Y187973D01*
G01X735974Y2539D02*
X806250D01*
G01X735974Y163760D02*
Y2539D01*
G01X806250Y163760D02*
X735974D01*
G01X725079Y182543D02*
X856476D01*
G01X725079Y406953D02*
Y182543D01*
G01X856476Y406953D02*
X725079D01*
G01X766465Y145216D02*
X766903Y144466D01*
G01D02*
X767428Y143966D01*
G01D02*
X768040Y143716D01*
G01D02*
X768740Y143966D01*
G01D02*
X769265Y144466D01*
G01D02*
X769790Y145216D01*
G01D02*
X769965Y146216D01*
G01D02*
Y151216D01*
G01X777378Y150341D02*
X777553Y149591D01*
G01D02*
X777465Y148841D01*
G01D02*
X777115Y148216D01*
G01D02*
X775365Y146966D01*
G01D02*
X774578Y146091D01*
G01D02*
X774053Y144840D01*
G01D02*
X773878Y143716D01*
G01D02*
X777553D01*
G01X781290Y145216D02*
X781815Y144341D01*
G01D02*
X782515Y143841D01*
G01D02*
X783303Y143716D01*
G01D02*
X784003Y143841D01*
G01D02*
X784703Y144466D01*
G01D02*
X785140Y145216D01*
G01X785053Y146840D02*
X784440Y147466D01*
G01D02*
X783828Y147716D01*
G01D02*
X783040D01*
G01X783828D02*
X784353Y148091D01*
G01D02*
X784790Y148716D01*
G01D02*
X784965Y149466D01*
G01X774053Y149966D02*
X774578Y150716D01*
G01D02*
X775190Y151091D01*
G01D02*
X775890Y151216D01*
G01D02*
X776765Y150966D01*
G01D02*
X777378Y150341D01*
G01X784965Y149466D02*
X784790Y150216D01*
G01D02*
X784353Y150841D01*
G01D02*
X783565Y151216D01*
G01D02*
X782778Y151091D01*
G01D02*
X781990Y150591D01*
G01X781528Y288236D02*
X781965Y287486D01*
G01D02*
X782490Y286986D01*
G01D02*
X783102Y286736D01*
G01D02*
X783803Y286986D01*
G01D02*
X784328Y287486D01*
G01D02*
X784853Y288236D01*
G01X802565Y76136D02*
X798715Y70636D01*
G01Y76136D02*
X802565Y70636D01*
G01X803265Y73386D02*
X798015D01*
G01X785140Y145216D02*
X785228Y145966D01*
G01D02*
X785053Y146840D01*
G01X784853Y288236D02*
X785028Y289236D01*
G01D02*
Y294236D01*
G01X792528Y291861D02*
X792177Y291236D01*
G01D02*
X790428Y289986D01*
G01D02*
X789640Y289111D01*
G01D02*
X789115Y287861D01*
G01D02*
X788940Y286736D01*
G01D02*
X792615D01*
G01X799328D02*
Y294236D01*
G01D02*
X796090Y288861D01*
G01D02*
X800465D01*
G01X789115Y292986D02*
X789640Y293736D01*
G01D02*
X790253Y294111D01*
G01D02*
X790953Y294236D01*
G01D02*
X791828Y293986D01*
G01D02*
X792440Y293361D01*
G01D02*
X792615Y292611D01*
G01D02*
X792528Y291861D01*
G01X806250Y2539D02*
Y163760D01*
G01X800640Y69636D02*
Y77136D01*
G01X841705Y78976D02*
X839455D01*
G01D02*
Y79476D01*
G01D02*
X839567Y79636D01*
G01D02*
X839717Y79736D01*
G01D02*
X840017Y79776D01*
G01D02*
X840317Y79736D01*
G01D02*
X840505Y79616D01*
G01D02*
X840617Y79476D01*
G01D02*
Y78976D01*
G01Y79476D02*
X841705Y79776D01*
G01Y80686D02*
X841217Y80726D01*
G01D02*
X840805Y80786D01*
G01D02*
X840430Y80866D01*
G01D02*
X840017Y80966D01*
G01D02*
X839455Y81126D01*
G01D02*
Y80326D01*
G01X841705Y82076D02*
X839455D01*
G01D02*
X839905Y81836D01*
G01X841705D02*
Y82316D01*
G01X836722Y72865D02*
Y87695D01*
G01X844475Y72865D02*
X836722D01*
G01X844475Y87695D02*
Y72865D01*
G01X836722Y87695D02*
X844475D01*
G01X842899Y263344D02*
X839049Y257844D01*
G01X840974Y256844D02*
Y264344D01*
G01X839049Y263344D02*
X842899Y257844D01*
G01X843599Y260594D02*
X838349D01*
G01X856476Y182543D02*
Y406953D01*
G01X919163Y168060D02*
G03X899085I-10039J14597D01*
G01X899085Y147224D02*
G03X919163I10039J0D01*
G01X899085D02*
Y168060D01*
G01X919163D02*
Y147224D01*
G01X973199Y61004D02*
G03X990915Y78720I0J17717D01*
G01X984065Y352146D02*
G03X966348Y369862I-17717J0D01*
G01X990915Y131634D02*
G03X987963Y134587I-2953J0D01*
G01X984065Y137539D02*
Y352146D01*
G01Y137539D02*
G03X987018Y134587I2953J0D01*
G01X987963D02*
X987018D01*
G01X990915Y78720D02*
Y131634D01*
G54D12*
G01X1178490Y-581900D02*
G03I-3990J0D01*
G01X1173300Y-584000D02*
Y-579800D01*
X1175100D01*
G01X1174800D02*
G02X1175550Y-580550I0J-750D01*
G01Y-580850D01*
G02X1174650Y-581750I-900J0D01*
G01X1174050D01*
G01X1174950Y-581900D02*
X1175700Y-584000D01*
G54D13*
G01X1400000Y1220000D02*
X595000D01*
G01Y1240000D02*
Y1220000D01*
G01Y1300000D02*
Y1240000D01*
G01X1400000Y1250000D02*
X595000D01*
G01Y1275000D02*
X1400000D01*
G01X650000Y1250000D02*
Y1220000D01*
G01Y1275000D02*
Y1250000D01*
G01X890000D02*
Y1220000D01*
G01Y1275000D02*
Y1250000D01*
G01X990000D02*
Y1220000D01*
G01Y1275000D02*
Y1250000D01*
G01X1060000D02*
Y1220000D01*
G01Y1275000D02*
Y1250000D01*
G01X1160000D02*
Y1220000D01*
G01Y1275000D02*
Y1250000D01*
G01X1230000D02*
Y1220000D01*
G01Y1275000D02*
Y1250000D01*
G01X1317980Y1249120D02*
Y1219120D01*
G01Y1274120D02*
Y1249120D01*
G54D14*
G01X961015Y-790000D02*
Y-777500D01*
X967685Y-790000D01*
Y-777500D01*
G01X976150Y-790000D02*
X974990Y-789792D01*
X973975Y-788959D01*
X973105Y-787708D01*
X972525Y-786250D01*
X972235Y-784583D01*
Y-782917D01*
X972525Y-781250D01*
X973105Y-779792D01*
X973975Y-778542D01*
X974990Y-777708D01*
X976150Y-777500D01*
X977310Y-777708D01*
X978325Y-778542D01*
X979195Y-779792D01*
X979775Y-781250D01*
X980065Y-782917D01*
Y-784583D01*
X979775Y-786250D01*
X979195Y-787708D01*
X978325Y-788959D01*
X977310Y-789792D01*
X976150Y-790000D01*
G01X984615D02*
Y-777500D01*
X991285Y-790000D01*
Y-777500D01*
G01X1002650Y-790000D02*
X996850D01*
Y-777500D01*
X1002650D01*
G01X1000330Y-783542D02*
X996850D01*
G54D15*
G01X-1900000Y250000D02*
X-1910000Y255000D01*
Y245000D01*
X-1900000Y250000D01*
G01Y-800000D02*
X1400000D01*
Y1300000D01*
X-1900000D01*
Y-800000D01*
G01X-1670000Y1300000D02*
Y1205000D01*
X-1900000D01*
G01X-200000Y-800000D02*
X-205000Y-810000D01*
X-195000D01*
X-200000Y-800000D01*
G01Y1300000D02*
X-195000Y1310000D01*
X-205000D01*
X-200000Y1300000D01*
G01X1400000Y250000D02*
X1410000Y245000D01*
Y255000D01*
X1400000Y250000D01*
G54D16*
G01X-1900000Y-300000D02*
X-1950000D01*
G01Y250000D02*
X-1900000D01*
G01Y800000D02*
X-1950000D01*
G01X-1499190Y726820D02*
X-1500240Y727570D01*
X-1501465Y728070D01*
X-1502865D01*
X-1504440Y727320D01*
X-1505665Y726070D01*
X-1506540Y724570D01*
X-1507240Y722070D01*
X-1507415Y719820D01*
X-1507065Y717570D01*
X-1506540Y716070D01*
X-1505490Y714570D01*
X-1504265Y713570D01*
X-1503040Y713070D01*
X-1501815D01*
X-1500590Y713570D01*
X-1499540Y714320D01*
X-1498665Y715320D01*
G01X-1493215Y713070D02*
X-1488840Y728070D01*
X-1484465Y713070D01*
G01X-1486040Y718320D02*
X-1491640D01*
G01X-1474640Y728070D02*
Y713070D01*
G01X-1478665Y728070D02*
X-1470615D01*
G01X-1464115Y713070D02*
Y728070D01*
G01X-1456765D02*
Y713070D01*
G01Y720570D02*
X-1464115D01*
G01X-1446240Y713070D02*
X-1447640Y713320D01*
X-1448865Y714320D01*
X-1449915Y715820D01*
X-1450615Y717570D01*
X-1450965Y719570D01*
Y721570D01*
X-1450615Y723570D01*
X-1449915Y725320D01*
X-1448865Y726820D01*
X-1447640Y727820D01*
X-1446240Y728070D01*
X-1444840Y727820D01*
X-1443615Y726820D01*
X-1442565Y725320D01*
X-1441865Y723570D01*
X-1441515Y721570D01*
Y719570D01*
X-1441865Y717570D01*
X-1442565Y715820D01*
X-1443615Y714320D01*
X-1444840Y713320D01*
X-1446240Y713070D01*
G01X-1435890D02*
Y728070D01*
X-1432390D01*
X-1430990Y727320D01*
X-1429940Y726320D01*
X-1429065Y724820D01*
X-1428365Y723070D01*
X-1428190Y720570D01*
X-1428365Y718070D01*
X-1429065Y716320D01*
X-1429940Y714820D01*
X-1430990Y713820D01*
X-1432390Y713070D01*
X-1435890D01*
G01X-1414340D02*
X-1421340D01*
Y728070D01*
X-1414340D01*
G01X-1417140Y720820D02*
X-1421340D01*
G01X-1385940Y713070D02*
X-1392940D01*
Y728070D01*
X-1385940D01*
G01X-1388740Y720820D02*
X-1392940D01*
G01X-1379265Y713070D02*
Y728070D01*
X-1371215Y713070D01*
Y728070D01*
G01X-1364890Y713070D02*
Y728070D01*
X-1361390D01*
X-1359990Y727320D01*
X-1358940Y726320D01*
X-1358065Y724820D01*
X-1357365Y723070D01*
X-1357190Y720570D01*
X-1357365Y718070D01*
X-1358065Y716320D01*
X-1358940Y714820D01*
X-1359990Y713820D01*
X-1361390Y713070D01*
X-1364890D01*
G01X-1332640D02*
X-1334040Y713320D01*
X-1335265Y714320D01*
X-1336315Y715820D01*
X-1337015Y717570D01*
X-1337365Y719570D01*
Y721570D01*
X-1337015Y723570D01*
X-1336315Y725320D01*
X-1335265Y726820D01*
X-1334040Y727820D01*
X-1332640Y728070D01*
X-1331240Y727820D01*
X-1330015Y726820D01*
X-1328965Y725320D01*
X-1328265Y723570D01*
X-1327915Y721570D01*
Y719570D01*
X-1328265Y717570D01*
X-1328965Y715820D01*
X-1330015Y714320D01*
X-1331240Y713320D01*
X-1332640Y713070D01*
G01X-1321765D02*
Y728070D01*
X-1315115D01*
G01X-1317565Y720820D02*
X-1321765D01*
G01X-1293890Y713070D02*
Y728070D01*
X-1290390D01*
X-1288990Y727320D01*
X-1287940Y726320D01*
X-1287065Y724820D01*
X-1286365Y723070D01*
X-1286190Y720570D01*
X-1286365Y718070D01*
X-1287065Y716320D01*
X-1287940Y714820D01*
X-1288990Y713820D01*
X-1290390Y713070D01*
X-1293890D01*
G01X-1277940Y728070D02*
X-1273740D01*
G01X-1275840D02*
Y713070D01*
G01X-1277940D02*
X-1273740D01*
G01X-1261640D02*
X-1263040Y713320D01*
X-1264265Y714320D01*
X-1265315Y715820D01*
X-1266015Y717570D01*
X-1266365Y719570D01*
Y721570D01*
X-1266015Y723570D01*
X-1265315Y725320D01*
X-1264265Y726820D01*
X-1263040Y727820D01*
X-1261640Y728070D01*
X-1260240Y727820D01*
X-1259015Y726820D01*
X-1257965Y725320D01*
X-1257265Y723570D01*
X-1256915Y721570D01*
Y719570D01*
X-1257265Y717570D01*
X-1257965Y715820D01*
X-1259015Y714320D01*
X-1260240Y713320D01*
X-1261640Y713070D01*
G01X-1251290D02*
Y728070D01*
X-1247790D01*
X-1246390Y727320D01*
X-1245340Y726320D01*
X-1244465Y724820D01*
X-1243765Y723070D01*
X-1243590Y720570D01*
X-1243765Y718070D01*
X-1244465Y716320D01*
X-1245340Y714820D01*
X-1246390Y713820D01*
X-1247790Y713070D01*
X-1251290D01*
G01X-1229740D02*
X-1236740D01*
Y728070D01*
X-1229740D01*
G01X-1232540Y720820D02*
X-1236740D01*
G01X-1222715Y715070D02*
X-1221315Y713820D01*
X-1219740Y713070D01*
X-1218340D01*
X-1216940Y713820D01*
X-1215890Y715070D01*
X-1215365Y716820D01*
X-1215715Y718570D01*
X-1216590Y720070D01*
X-1218165Y721070D01*
X-1220265Y721570D01*
X-1221490Y722570D01*
X-1222015Y724320D01*
X-1221665Y726070D01*
X-1220790Y727320D01*
X-1219565Y728070D01*
X-1218340D01*
X-1217115Y727570D01*
X-1216065Y726320D01*
G01X-1204840Y712570D02*
X-1205190Y712820D01*
Y713320D01*
X-1204840Y713570D01*
X-1204490Y713320D01*
Y712820D01*
X-1204840Y712570D01*
G01X-1506540Y743070D02*
Y758070D01*
X-1502340D01*
X-1500940Y757320D01*
X-1499890Y755570D01*
X-1499540Y753570D01*
X-1499890Y751570D01*
X-1500765Y750070D01*
X-1502340Y749320D01*
X-1506540D01*
G01X-1488840Y743070D02*
X-1490240Y743320D01*
X-1491465Y744320D01*
X-1492515Y745820D01*
X-1493215Y747570D01*
X-1493565Y749570D01*
Y751570D01*
X-1493215Y753570D01*
X-1492515Y755320D01*
X-1491465Y756820D01*
X-1490240Y757820D01*
X-1488840Y758070D01*
X-1487440Y757820D01*
X-1486215Y756820D01*
X-1485165Y755320D01*
X-1484465Y753570D01*
X-1484115Y751570D01*
Y749570D01*
X-1484465Y747570D01*
X-1485165Y745820D01*
X-1486215Y744320D01*
X-1487440Y743320D01*
X-1488840Y743070D01*
G01X-1478315Y745070D02*
X-1476915Y743820D01*
X-1475340Y743070D01*
X-1473940D01*
X-1472540Y743820D01*
X-1471490Y745070D01*
X-1470965Y746820D01*
X-1471315Y748570D01*
X-1472190Y750070D01*
X-1473765Y751070D01*
X-1475865Y751570D01*
X-1477090Y752570D01*
X-1477615Y754320D01*
X-1477265Y756070D01*
X-1476390Y757320D01*
X-1475165Y758070D01*
X-1473940D01*
X-1472715Y757570D01*
X-1471665Y756320D01*
G01X-1462540Y758070D02*
X-1458340D01*
G01X-1460440D02*
Y743070D01*
G01X-1462540D02*
X-1458340D01*
G01X-1446240Y758070D02*
Y743070D01*
G01X-1450265Y758070D02*
X-1442215D01*
G01X-1434140D02*
X-1429940D01*
G01X-1432040D02*
Y743070D01*
G01X-1434140D02*
X-1429940D01*
G01X-1422215Y758070D02*
X-1417840Y743070D01*
X-1413465Y758070D01*
G01X-1400140Y743070D02*
X-1407140D01*
Y758070D01*
X-1400140D01*
G01X-1402940Y750820D02*
X-1407140D01*
G01X-1371740Y743070D02*
X-1378740D01*
Y758070D01*
X-1371740D01*
G01X-1374540Y750820D02*
X-1378740D01*
G01X-1365065Y743070D02*
Y758070D01*
X-1357015Y743070D01*
Y758070D01*
G01X-1350690Y743070D02*
Y758070D01*
X-1347190D01*
X-1345790Y757320D01*
X-1344740Y756320D01*
X-1343865Y754820D01*
X-1343165Y753070D01*
X-1342990Y750570D01*
X-1343165Y748070D01*
X-1343865Y746320D01*
X-1344740Y744820D01*
X-1345790Y743820D01*
X-1347190Y743070D01*
X-1350690D01*
G01X-1318440D02*
X-1319840Y743320D01*
X-1321065Y744320D01*
X-1322115Y745820D01*
X-1322815Y747570D01*
X-1323165Y749570D01*
Y751570D01*
X-1322815Y753570D01*
X-1322115Y755320D01*
X-1321065Y756820D01*
X-1319840Y757820D01*
X-1318440Y758070D01*
X-1317040Y757820D01*
X-1315815Y756820D01*
X-1314765Y755320D01*
X-1314065Y753570D01*
X-1313715Y751570D01*
Y749570D01*
X-1314065Y747570D01*
X-1314765Y745820D01*
X-1315815Y744320D01*
X-1317040Y743320D01*
X-1318440Y743070D01*
G01X-1307565D02*
Y758070D01*
X-1300915D01*
G01X-1303365Y750820D02*
X-1307565D01*
G01X-1279340Y743070D02*
Y758070D01*
X-1275140D01*
X-1273740Y757320D01*
X-1272690Y755570D01*
X-1272340Y753570D01*
X-1272690Y751570D01*
X-1273565Y750070D01*
X-1275140Y749320D01*
X-1279340D01*
G01X-1261640Y743070D02*
X-1263040Y743320D01*
X-1264265Y744320D01*
X-1265315Y745820D01*
X-1266015Y747570D01*
X-1266365Y749570D01*
Y751570D01*
X-1266015Y753570D01*
X-1265315Y755320D01*
X-1264265Y756820D01*
X-1263040Y757820D01*
X-1261640Y758070D01*
X-1260240Y757820D01*
X-1259015Y756820D01*
X-1257965Y755320D01*
X-1257265Y753570D01*
X-1256915Y751570D01*
Y749570D01*
X-1257265Y747570D01*
X-1257965Y745820D01*
X-1259015Y744320D01*
X-1260240Y743320D01*
X-1261640Y743070D01*
G01X-1250940Y758070D02*
Y743070D01*
X-1243940D01*
G01X-1237615D02*
X-1233240Y758070D01*
X-1228865Y743070D01*
G01X-1230440Y748320D02*
X-1236040D01*
G01X-1222540Y743070D02*
Y758070D01*
X-1218165D01*
X-1216765Y757320D01*
X-1215890Y756320D01*
X-1215540Y754320D01*
X-1215890Y752320D01*
X-1216940Y751070D01*
X-1218165Y750320D01*
X-1222540D01*
G01X-1218165D02*
X-1215540Y743070D01*
G01X-1206940Y758070D02*
X-1202740D01*
G01X-1204840D02*
Y743070D01*
G01X-1206940D02*
X-1202740D01*
G01X-1193965Y758070D02*
X-1187315D01*
X-1193965Y743070D01*
X-1187315D01*
G01X-1172940D02*
X-1179940D01*
Y758070D01*
X-1172940D01*
G01X-1175740Y750820D02*
X-1179940D01*
G01X-1166090Y743070D02*
Y758070D01*
X-1162590D01*
X-1161190Y757320D01*
X-1160140Y756320D01*
X-1159265Y754820D01*
X-1158565Y753070D01*
X-1158390Y750570D01*
X-1158565Y748070D01*
X-1159265Y746320D01*
X-1160140Y744820D01*
X-1161190Y743820D01*
X-1162590Y743070D01*
X-1166090D01*
G01X-1129990Y756820D02*
X-1131040Y757570D01*
X-1132265Y758070D01*
X-1133665D01*
X-1135240Y757320D01*
X-1136465Y756070D01*
X-1137340Y754570D01*
X-1138040Y752070D01*
X-1138215Y749820D01*
X-1137865Y747570D01*
X-1137340Y746070D01*
X-1136290Y744570D01*
X-1135065Y743570D01*
X-1133840Y743070D01*
X-1132615D01*
X-1131390Y743570D01*
X-1130340Y744320D01*
X-1129465Y745320D01*
G01X-1124015Y743070D02*
X-1119640Y758070D01*
X-1115265Y743070D01*
G01X-1116840Y748320D02*
X-1122440D01*
G01X-1108940Y743070D02*
Y758070D01*
X-1104740D01*
X-1103340Y757320D01*
X-1102290Y755570D01*
X-1101940Y753570D01*
X-1102290Y751570D01*
X-1103165Y750070D01*
X-1104740Y749320D01*
X-1108940D01*
G01X-1095615Y743070D02*
X-1091240Y758070D01*
X-1086865Y743070D01*
G01X-1088440Y748320D02*
X-1094040D01*
G01X-1073190Y756820D02*
X-1074240Y757570D01*
X-1075465Y758070D01*
X-1076865D01*
X-1078440Y757320D01*
X-1079665Y756070D01*
X-1080540Y754570D01*
X-1081240Y752070D01*
X-1081415Y749820D01*
X-1081065Y747570D01*
X-1080540Y746070D01*
X-1079490Y744570D01*
X-1078265Y743570D01*
X-1077040Y743070D01*
X-1075815D01*
X-1074590Y743570D01*
X-1073540Y744320D01*
X-1072665Y745320D01*
G01X-1064940Y758070D02*
X-1060740D01*
G01X-1062840D02*
Y743070D01*
G01X-1064940D02*
X-1060740D01*
G01X-1048640Y758070D02*
Y743070D01*
G01X-1052665Y758070D02*
X-1044615D01*
G01X-1034440Y743070D02*
X-1035840Y743320D01*
X-1037065Y744320D01*
X-1038115Y745820D01*
X-1038815Y747570D01*
X-1039165Y749570D01*
Y751570D01*
X-1038815Y753570D01*
X-1038115Y755320D01*
X-1037065Y756820D01*
X-1035840Y757820D01*
X-1034440Y758070D01*
X-1033040Y757820D01*
X-1031815Y756820D01*
X-1030765Y755320D01*
X-1030065Y753570D01*
X-1029715Y751570D01*
Y749570D01*
X-1030065Y747570D01*
X-1030765Y745820D01*
X-1031815Y744320D01*
X-1033040Y743320D01*
X-1034440Y743070D01*
G01X-1023740D02*
Y758070D01*
X-1019365D01*
X-1017965Y757320D01*
X-1017090Y756320D01*
X-1016740Y754320D01*
X-1017090Y752320D01*
X-1018140Y751070D01*
X-1019365Y750320D01*
X-1023740D01*
G01X-1019365D02*
X-1016740Y743070D01*
G01X-1009715Y745070D02*
X-1008315Y743820D01*
X-1006740Y743070D01*
X-1005340D01*
X-1003940Y743820D01*
X-1002890Y745070D01*
X-1002365Y746820D01*
X-1002715Y748570D01*
X-1003590Y750070D01*
X-1005165Y751070D01*
X-1007265Y751570D01*
X-1008490Y752570D01*
X-1009015Y754320D01*
X-1008665Y756070D01*
X-1007790Y757320D01*
X-1006565Y758070D01*
X-1005340D01*
X-1004115Y757570D01*
X-1003065Y756320D01*
G01X-991840Y742570D02*
X-992190Y742820D01*
Y743320D01*
X-991840Y743570D01*
X-991490Y743320D01*
Y742820D01*
X-991840Y742570D01*
G01X-1506540Y773070D02*
Y788070D01*
X-1502340D01*
X-1500940Y787320D01*
X-1499890Y785570D01*
X-1499540Y783570D01*
X-1499890Y781570D01*
X-1500765Y780070D01*
X-1502340Y779320D01*
X-1506540D01*
G01X-1490940Y788070D02*
X-1486740D01*
G01X-1488840D02*
Y773070D01*
G01X-1490940D02*
X-1486740D01*
G01X-1478665D02*
Y788070D01*
X-1470615Y773070D01*
Y788070D01*
G01X-1446240Y773070D02*
Y788070D01*
X-1448340Y785070D01*
G01Y773070D02*
X-1444140D01*
G01X-1417840D02*
X-1419240Y773320D01*
X-1420465Y774320D01*
X-1421515Y775820D01*
X-1422215Y777570D01*
X-1422565Y779570D01*
Y781570D01*
X-1422215Y783570D01*
X-1421515Y785320D01*
X-1420465Y786820D01*
X-1419240Y787820D01*
X-1417840Y788070D01*
X-1416440Y787820D01*
X-1415215Y786820D01*
X-1414165Y785320D01*
X-1413465Y783570D01*
X-1413115Y781570D01*
Y779570D01*
X-1413465Y777570D01*
X-1414165Y775820D01*
X-1415215Y774320D01*
X-1416440Y773320D01*
X-1417840Y773070D01*
G01X-1406965D02*
Y788070D01*
X-1400315D01*
G01X-1402765Y780820D02*
X-1406965D01*
G01X-1377340Y788070D02*
X-1373140D01*
G01X-1375240D02*
Y773070D01*
G01X-1377340D02*
X-1373140D01*
G01X-1357190Y786820D02*
X-1358240Y787570D01*
X-1359465Y788070D01*
X-1360865D01*
X-1362440Y787320D01*
X-1363665Y786070D01*
X-1364540Y784570D01*
X-1365240Y782070D01*
X-1365415Y779820D01*
X-1365065Y777570D01*
X-1364540Y776070D01*
X-1363490Y774570D01*
X-1362265Y773570D01*
X-1361040Y773070D01*
X-1359815D01*
X-1358590Y773570D01*
X-1357540Y774320D01*
X-1356665Y775320D01*
G01X-1346840Y783070D02*
X-1345090Y786195D01*
Y788070D01*
X-1346402D01*
Y786195D01*
X-1345090D01*
G01X-1336315Y775070D02*
X-1334915Y773820D01*
X-1333340Y773070D01*
X-1331940D01*
X-1330540Y773820D01*
X-1329490Y775070D01*
X-1328965Y776820D01*
X-1329315Y778570D01*
X-1330190Y780070D01*
X-1331765Y781070D01*
X-1333865Y781570D01*
X-1335090Y782570D01*
X-1335615Y784320D01*
X-1335265Y786070D01*
X-1334390Y787320D01*
X-1333165Y788070D01*
X-1331940D01*
X-1330715Y787570D01*
X-1329665Y786320D01*
G01X-1308615Y773070D02*
X-1304240Y788070D01*
X-1299865Y773070D01*
G01X-1301440Y778320D02*
X-1307040D01*
G01X-1294065Y773070D02*
Y788070D01*
X-1286015Y773070D01*
Y788070D01*
G01X-1279690Y773070D02*
Y788070D01*
X-1276190D01*
X-1274790Y787320D01*
X-1273740Y786320D01*
X-1272865Y784820D01*
X-1272165Y783070D01*
X-1271990Y780570D01*
X-1272165Y778070D01*
X-1272865Y776320D01*
X-1273740Y774820D01*
X-1274790Y773820D01*
X-1276190Y773070D01*
X-1279690D01*
G01X-1243590Y786820D02*
X-1244640Y787570D01*
X-1245865Y788070D01*
X-1247265D01*
X-1248840Y787320D01*
X-1250065Y786070D01*
X-1250940Y784570D01*
X-1251640Y782070D01*
X-1251815Y779820D01*
X-1251465Y777570D01*
X-1250940Y776070D01*
X-1249890Y774570D01*
X-1248665Y773570D01*
X-1247440Y773070D01*
X-1246215D01*
X-1244990Y773570D01*
X-1243940Y774320D01*
X-1243065Y775320D01*
G01X-1233240Y773070D02*
X-1234640Y773320D01*
X-1235865Y774320D01*
X-1236915Y775820D01*
X-1237615Y777570D01*
X-1237965Y779570D01*
Y781570D01*
X-1237615Y783570D01*
X-1236915Y785320D01*
X-1235865Y786820D01*
X-1234640Y787820D01*
X-1233240Y788070D01*
X-1231840Y787820D01*
X-1230615Y786820D01*
X-1229565Y785320D01*
X-1228865Y783570D01*
X-1228515Y781570D01*
Y779570D01*
X-1228865Y777570D01*
X-1229565Y775820D01*
X-1230615Y774320D01*
X-1231840Y773320D01*
X-1233240Y773070D01*
G01X-1223065D02*
Y788070D01*
X-1215015Y773070D01*
Y788070D01*
G01X-1208865Y773070D02*
Y788070D01*
X-1200815Y773070D01*
Y788070D01*
G01X-1187140Y773070D02*
X-1194140D01*
Y788070D01*
X-1187140D01*
G01X-1189940Y780820D02*
X-1194140D01*
G01X-1172590Y786820D02*
X-1173640Y787570D01*
X-1174865Y788070D01*
X-1176265D01*
X-1177840Y787320D01*
X-1179065Y786070D01*
X-1179940Y784570D01*
X-1180640Y782070D01*
X-1180815Y779820D01*
X-1180465Y777570D01*
X-1179940Y776070D01*
X-1178890Y774570D01*
X-1177665Y773570D01*
X-1176440Y773070D01*
X-1175215D01*
X-1173990Y773570D01*
X-1172940Y774320D01*
X-1172065Y775320D01*
G01X-1162240Y788070D02*
Y773070D01*
G01X-1166265Y788070D02*
X-1158215D01*
G01X-1148040Y773070D02*
X-1149440Y773320D01*
X-1150665Y774320D01*
X-1151715Y775820D01*
X-1152415Y777570D01*
X-1152765Y779570D01*
Y781570D01*
X-1152415Y783570D01*
X-1151715Y785320D01*
X-1150665Y786820D01*
X-1149440Y787820D01*
X-1148040Y788070D01*
X-1146640Y787820D01*
X-1145415Y786820D01*
X-1144365Y785320D01*
X-1143665Y783570D01*
X-1143315Y781570D01*
Y779570D01*
X-1143665Y777570D01*
X-1144365Y775820D01*
X-1145415Y774320D01*
X-1146640Y773320D01*
X-1148040Y773070D01*
G01X-1137340D02*
Y788070D01*
X-1132965D01*
X-1131565Y787320D01*
X-1130690Y786320D01*
X-1130340Y784320D01*
X-1130690Y782320D01*
X-1131740Y781070D01*
X-1132965Y780320D01*
X-1137340D01*
G01X-1132965D02*
X-1130340Y773070D01*
G01X-1123315Y775070D02*
X-1121915Y773820D01*
X-1120340Y773070D01*
X-1118940D01*
X-1117540Y773820D01*
X-1116490Y775070D01*
X-1115965Y776820D01*
X-1116315Y778570D01*
X-1117190Y780070D01*
X-1118765Y781070D01*
X-1120865Y781570D01*
X-1122090Y782570D01*
X-1122615Y784320D01*
X-1122265Y786070D01*
X-1121390Y787320D01*
X-1120165Y788070D01*
X-1118940D01*
X-1117715Y787570D01*
X-1116665Y786320D01*
G01X-1105440Y772570D02*
X-1105790Y772820D01*
Y773320D01*
X-1105440Y773570D01*
X-1105090Y773320D01*
Y772820D01*
X-1105440Y772570D01*
G01X-1543540Y803070D02*
Y818070D01*
X-1550015Y807320D01*
X-1541265D01*
G01X-1531440Y802570D02*
X-1531790Y802820D01*
Y803320D01*
X-1531440Y803570D01*
X-1531090Y803320D01*
Y802820D01*
X-1531440Y802570D01*
G01X-1506715Y805070D02*
X-1505315Y803820D01*
X-1503740Y803070D01*
X-1502340D01*
X-1500940Y803820D01*
X-1499890Y805070D01*
X-1499365Y806820D01*
X-1499715Y808570D01*
X-1500590Y810070D01*
X-1502165Y811070D01*
X-1504265Y811570D01*
X-1505490Y812570D01*
X-1506015Y814320D01*
X-1505665Y816070D01*
X-1504790Y817320D01*
X-1503565Y818070D01*
X-1502340D01*
X-1501115Y817570D01*
X-1500065Y816320D01*
G01X-1488840Y803070D02*
X-1490240Y803320D01*
X-1491465Y804320D01*
X-1492515Y805820D01*
X-1493215Y807570D01*
X-1493565Y809570D01*
Y811570D01*
X-1493215Y813570D01*
X-1492515Y815320D01*
X-1491465Y816820D01*
X-1490240Y817820D01*
X-1488840Y818070D01*
X-1487440Y817820D01*
X-1486215Y816820D01*
X-1485165Y815320D01*
X-1484465Y813570D01*
X-1484115Y811570D01*
Y809570D01*
X-1484465Y807570D01*
X-1485165Y805820D01*
X-1486215Y804320D01*
X-1487440Y803320D01*
X-1488840Y803070D01*
G01X-1487440Y807070D02*
X-1485340Y803070D01*
G01X-1478490Y818070D02*
Y807320D01*
X-1477790Y805070D01*
X-1476390Y803570D01*
X-1474640Y803070D01*
X-1472890Y803570D01*
X-1471490Y805070D01*
X-1470790Y807320D01*
Y818070D01*
G01X-1464815Y803070D02*
X-1460440Y818070D01*
X-1456065Y803070D01*
G01X-1457640Y808320D02*
X-1463240D01*
G01X-1449740Y803070D02*
Y818070D01*
X-1445365D01*
X-1443965Y817320D01*
X-1443090Y816320D01*
X-1442740Y814320D01*
X-1443090Y812320D01*
X-1444140Y811070D01*
X-1445365Y810320D01*
X-1449740D01*
G01X-1445365D02*
X-1442740Y803070D01*
G01X-1428540D02*
X-1435540D01*
Y818070D01*
X-1428540D01*
G01X-1431340Y810820D02*
X-1435540D01*
G01X-1407140Y803070D02*
Y818070D01*
X-1402940D01*
X-1401540Y817320D01*
X-1400490Y815570D01*
X-1400140Y813570D01*
X-1400490Y811570D01*
X-1401365Y810070D01*
X-1402940Y809320D01*
X-1407140D01*
G01X-1393815Y803070D02*
X-1389440Y818070D01*
X-1385065Y803070D01*
G01X-1386640Y808320D02*
X-1392240D01*
G01X-1379090Y803070D02*
Y818070D01*
X-1375590D01*
X-1374190Y817320D01*
X-1373140Y816320D01*
X-1372265Y814820D01*
X-1371565Y813070D01*
X-1371390Y810570D01*
X-1371565Y808070D01*
X-1372265Y806320D01*
X-1373140Y804820D01*
X-1374190Y803820D01*
X-1375590Y803070D01*
X-1379090D01*
G01X-1364715Y805070D02*
X-1363315Y803820D01*
X-1361740Y803070D01*
X-1360340D01*
X-1358940Y803820D01*
X-1357890Y805070D01*
X-1357365Y806820D01*
X-1357715Y808570D01*
X-1358590Y810070D01*
X-1360165Y811070D01*
X-1362265Y811570D01*
X-1363490Y812570D01*
X-1364015Y814320D01*
X-1363665Y816070D01*
X-1362790Y817320D01*
X-1361565Y818070D01*
X-1360340D01*
X-1359115Y817570D01*
X-1358065Y816320D01*
G01X-1336490Y803070D02*
Y818070D01*
X-1332990D01*
X-1331590Y817320D01*
X-1330540Y816320D01*
X-1329665Y814820D01*
X-1328965Y813070D01*
X-1328790Y810570D01*
X-1328965Y808070D01*
X-1329665Y806320D01*
X-1330540Y804820D01*
X-1331590Y803820D01*
X-1332990Y803070D01*
X-1336490D01*
G01X-1314940D02*
X-1321940D01*
Y818070D01*
X-1314940D01*
G01X-1317740Y810820D02*
X-1321940D01*
G01X-1308265Y803070D02*
Y818070D01*
X-1300215Y803070D01*
Y818070D01*
G01X-1290040Y803070D02*
X-1291440Y803320D01*
X-1292665Y804320D01*
X-1293715Y805820D01*
X-1294415Y807570D01*
X-1294765Y809570D01*
Y811570D01*
X-1294415Y813570D01*
X-1293715Y815320D01*
X-1292665Y816820D01*
X-1291440Y817820D01*
X-1290040Y818070D01*
X-1288640Y817820D01*
X-1287415Y816820D01*
X-1286365Y815320D01*
X-1285665Y813570D01*
X-1285315Y811570D01*
Y809570D01*
X-1285665Y807570D01*
X-1286365Y805820D01*
X-1287415Y804320D01*
X-1288640Y803320D01*
X-1290040Y803070D01*
G01X-1275840Y818070D02*
Y803070D01*
G01X-1279865Y818070D02*
X-1271815D01*
G01X-1258140Y803070D02*
X-1265140D01*
Y818070D01*
X-1258140D01*
G01X-1260940Y810820D02*
X-1265140D01*
G01X-1233240Y818070D02*
Y803070D01*
G01X-1237265Y818070D02*
X-1229215D01*
G01X-1222715Y803070D02*
Y818070D01*
G01X-1215365D02*
Y803070D01*
G01Y810570D02*
X-1222715D01*
G01X-1201340Y803070D02*
X-1208340D01*
Y818070D01*
X-1201340D01*
G01X-1204140Y810820D02*
X-1208340D01*
G01X-1179765Y803070D02*
Y818070D01*
X-1173115D01*
G01X-1175565Y810820D02*
X-1179765D01*
G01X-1162240Y803070D02*
X-1163640Y803320D01*
X-1164865Y804320D01*
X-1165915Y805820D01*
X-1166615Y807570D01*
X-1166965Y809570D01*
Y811570D01*
X-1166615Y813570D01*
X-1165915Y815320D01*
X-1164865Y816820D01*
X-1163640Y817820D01*
X-1162240Y818070D01*
X-1160840Y817820D01*
X-1159615Y816820D01*
X-1158565Y815320D01*
X-1157865Y813570D01*
X-1157515Y811570D01*
Y809570D01*
X-1157865Y807570D01*
X-1158565Y805820D01*
X-1159615Y804320D01*
X-1160840Y803320D01*
X-1162240Y803070D01*
G01X-1151540Y818070D02*
Y803070D01*
X-1144540D01*
G01X-1137340Y818070D02*
Y803070D01*
X-1130340D01*
G01X-1119640D02*
X-1121040Y803320D01*
X-1122265Y804320D01*
X-1123315Y805820D01*
X-1124015Y807570D01*
X-1124365Y809570D01*
Y811570D01*
X-1124015Y813570D01*
X-1123315Y815320D01*
X-1122265Y816820D01*
X-1121040Y817820D01*
X-1119640Y818070D01*
X-1118240Y817820D01*
X-1117015Y816820D01*
X-1115965Y815320D01*
X-1115265Y813570D01*
X-1114915Y811570D01*
Y809570D01*
X-1115265Y807570D01*
X-1115965Y805820D01*
X-1117015Y804320D01*
X-1118240Y803320D01*
X-1119640Y803070D01*
G01X-1110690Y818070D02*
X-1108240Y803070D01*
X-1105440Y818070D01*
X-1102640Y803070D01*
X-1100190Y818070D01*
G01X-1093340D02*
X-1089140D01*
G01X-1091240D02*
Y803070D01*
G01X-1093340D02*
X-1089140D01*
G01X-1081065D02*
Y818070D01*
X-1073015Y803070D01*
Y818070D01*
G01X-1061790Y810570D02*
X-1058290D01*
Y806070D01*
X-1059340Y804570D01*
X-1060565Y803570D01*
X-1062315Y803070D01*
X-1064065Y803570D01*
X-1065290Y804570D01*
X-1066340Y806070D01*
X-1067040Y807820D01*
X-1067390Y809820D01*
Y811570D01*
X-1067040Y813070D01*
X-1066340Y814820D01*
X-1065290Y816320D01*
X-1064240Y817320D01*
X-1062840Y818070D01*
X-1061615D01*
X-1060215Y817570D01*
X-1059165Y816570D01*
G01X-1048640Y802570D02*
X-1048990Y802820D01*
Y803320D01*
X-1048640Y803570D01*
X-1048290Y803320D01*
Y802820D01*
X-1048640Y802570D01*
G01Y809320D02*
X-1048990Y809570D01*
Y810070D01*
X-1048640Y810320D01*
X-1048290Y810070D01*
Y809570D01*
X-1048640Y809320D01*
G01X-1549490Y841070D02*
X-1548440Y839320D01*
X-1547040Y838320D01*
X-1545465Y838070D01*
X-1544065Y838320D01*
X-1542665Y839570D01*
X-1541790Y841070D01*
X-1541615Y842570D01*
X-1541965Y844320D01*
X-1543190Y845570D01*
X-1544415Y846070D01*
X-1545990D01*
G01X-1544415D02*
X-1543365Y846820D01*
X-1542490Y848070D01*
X-1542140Y849570D01*
X-1542490Y851070D01*
X-1543365Y852320D01*
X-1544940Y853070D01*
X-1546515Y852820D01*
X-1548090Y851820D01*
G01X-1531440Y837570D02*
X-1531790Y837820D01*
Y838320D01*
X-1531440Y838570D01*
X-1531090Y838320D01*
Y837820D01*
X-1531440Y837570D01*
G01X-1506890Y853070D02*
Y842320D01*
X-1506190Y840070D01*
X-1504790Y838570D01*
X-1503040Y838070D01*
X-1501290Y838570D01*
X-1499890Y840070D01*
X-1499190Y842320D01*
Y853070D01*
G01X-1492515Y840070D02*
X-1491115Y838820D01*
X-1489540Y838070D01*
X-1488140D01*
X-1486740Y838820D01*
X-1485690Y840070D01*
X-1485165Y841820D01*
X-1485515Y843570D01*
X-1486390Y845070D01*
X-1487965Y846070D01*
X-1490065Y846570D01*
X-1491290Y847570D01*
X-1491815Y849320D01*
X-1491465Y851070D01*
X-1490590Y852320D01*
X-1489365Y853070D01*
X-1488140D01*
X-1486915Y852570D01*
X-1485865Y851320D01*
G01X-1471140Y838070D02*
X-1478140D01*
Y853070D01*
X-1471140D01*
G01X-1473940Y845820D02*
X-1478140D01*
G01X-1448340Y853070D02*
X-1444140D01*
G01X-1446240D02*
Y838070D01*
G01X-1448340D02*
X-1444140D01*
G01X-1435540D02*
Y853070D01*
X-1431340D01*
X-1429940Y852320D01*
X-1428890Y850570D01*
X-1428540Y848570D01*
X-1428890Y846570D01*
X-1429765Y845070D01*
X-1431340Y844320D01*
X-1435540D01*
G01X-1413990Y851820D02*
X-1415040Y852570D01*
X-1416265Y853070D01*
X-1417665D01*
X-1419240Y852320D01*
X-1420465Y851070D01*
X-1421340Y849570D01*
X-1422040Y847070D01*
X-1422215Y844820D01*
X-1421865Y842570D01*
X-1421340Y841070D01*
X-1420290Y839570D01*
X-1419065Y838570D01*
X-1417840Y838070D01*
X-1416615D01*
X-1415390Y838570D01*
X-1414340Y839320D01*
X-1413465Y840320D01*
G01X-1405915Y843070D02*
X-1401365D01*
G01X-1389790Y838070D02*
X-1389440Y841320D01*
X-1388915Y844070D01*
X-1388215Y846570D01*
X-1387340Y849320D01*
X-1385940Y853070D01*
X-1392940D01*
G01X-1375590Y838070D02*
X-1375240Y841320D01*
X-1374715Y844070D01*
X-1374015Y846570D01*
X-1373140Y849320D01*
X-1371740Y853070D01*
X-1378740D01*
G01X-1361040Y838070D02*
Y853070D01*
X-1363140Y850070D01*
G01Y838070D02*
X-1358940D01*
G01X-1346840D02*
Y853070D01*
X-1348940Y850070D01*
G01Y838070D02*
X-1344740D01*
G01X-1335790Y837570D02*
X-1329490Y853070D01*
G01X-1318790Y838070D02*
X-1318440Y841320D01*
X-1317915Y844070D01*
X-1317215Y846570D01*
X-1316340Y849320D01*
X-1314940Y853070D01*
X-1321940D01*
G01X-1304590Y838070D02*
X-1304240Y841320D01*
X-1303715Y844070D01*
X-1303015Y846570D01*
X-1302140Y849320D01*
X-1300740Y853070D01*
X-1307740D01*
G01X-1293365Y850570D02*
X-1292315Y852070D01*
X-1291090Y852820D01*
X-1289690Y853070D01*
X-1287940Y852570D01*
X-1286715Y851320D01*
X-1286365Y849820D01*
X-1286540Y848320D01*
X-1287240Y847070D01*
X-1290740Y844570D01*
X-1292315Y842820D01*
X-1293365Y840320D01*
X-1293715Y838070D01*
X-1286365D01*
G01X-1275840D02*
Y853070D01*
X-1277940Y850070D01*
G01Y838070D02*
X-1273740D01*
G01X-1248315Y833070D02*
X-1250065Y835570D01*
X-1250940Y838070D01*
Y848070D01*
X-1250065Y850570D01*
X-1248315Y853070D01*
G01X-1236740D02*
Y838070D01*
X-1229740D01*
G01X-1223415D02*
X-1219040Y853070D01*
X-1214665Y838070D01*
G01X-1216240Y843320D02*
X-1221840D01*
G01X-1204840Y853070D02*
Y838070D01*
G01X-1208865Y853070D02*
X-1200815D01*
G01X-1187140Y838070D02*
X-1194140D01*
Y853070D01*
X-1187140D01*
G01X-1189940Y845820D02*
X-1194140D01*
G01X-1180115Y840070D02*
X-1178715Y838820D01*
X-1177140Y838070D01*
X-1175740D01*
X-1174340Y838820D01*
X-1173290Y840070D01*
X-1172765Y841820D01*
X-1173115Y843570D01*
X-1173990Y845070D01*
X-1175565Y846070D01*
X-1177665Y846570D01*
X-1178890Y847570D01*
X-1179415Y849320D01*
X-1179065Y851070D01*
X-1178190Y852320D01*
X-1176965Y853070D01*
X-1175740D01*
X-1174515Y852570D01*
X-1173465Y851320D01*
G01X-1162240Y853070D02*
Y838070D01*
G01X-1166265Y853070D02*
X-1158215D01*
G01X-1137340Y838070D02*
Y853070D01*
X-1132965D01*
X-1131565Y852320D01*
X-1130690Y851320D01*
X-1130340Y849320D01*
X-1130690Y847320D01*
X-1131740Y846070D01*
X-1132965Y845320D01*
X-1137340D01*
G01X-1132965D02*
X-1130340Y838070D01*
G01X-1116140D02*
X-1123140D01*
Y853070D01*
X-1116140D01*
G01X-1118940Y845820D02*
X-1123140D01*
G01X-1109815Y853070D02*
X-1105440Y838070D01*
X-1101065Y853070D01*
G01X-1093340D02*
X-1089140D01*
G01X-1091240D02*
Y838070D01*
G01X-1093340D02*
X-1089140D01*
G01X-1080715Y840070D02*
X-1079315Y838820D01*
X-1077740Y838070D01*
X-1076340D01*
X-1074940Y838820D01*
X-1073890Y840070D01*
X-1073365Y841820D01*
X-1073715Y843570D01*
X-1074590Y845070D01*
X-1076165Y846070D01*
X-1078265Y846570D01*
X-1079490Y847570D01*
X-1080015Y849320D01*
X-1079665Y851070D01*
X-1078790Y852320D01*
X-1077565Y853070D01*
X-1076340D01*
X-1075115Y852570D01*
X-1074065Y851320D01*
G01X-1064940Y853070D02*
X-1060740D01*
G01X-1062840D02*
Y838070D01*
G01X-1064940D02*
X-1060740D01*
G01X-1048640D02*
X-1050040Y838320D01*
X-1051265Y839320D01*
X-1052315Y840820D01*
X-1053015Y842570D01*
X-1053365Y844570D01*
Y846570D01*
X-1053015Y848570D01*
X-1052315Y850320D01*
X-1051265Y851820D01*
X-1050040Y852820D01*
X-1048640Y853070D01*
X-1047240Y852820D01*
X-1046015Y851820D01*
X-1044965Y850320D01*
X-1044265Y848570D01*
X-1043915Y846570D01*
Y844570D01*
X-1044265Y842570D01*
X-1044965Y840820D01*
X-1046015Y839320D01*
X-1047240Y838320D01*
X-1048640Y838070D01*
G01X-1038465D02*
Y853070D01*
X-1030415Y838070D01*
Y853070D01*
G01X-1019365Y833070D02*
X-1017615Y835570D01*
X-1016740Y838070D01*
Y848070D01*
X-1017615Y850570D01*
X-1019365Y853070D01*
G01X-995165Y838070D02*
Y853070D01*
X-988515D01*
G01X-990965Y845820D02*
X-995165D01*
G01X-977640Y838070D02*
X-979040Y838320D01*
X-980265Y839320D01*
X-981315Y840820D01*
X-982015Y842570D01*
X-982365Y844570D01*
Y846570D01*
X-982015Y848570D01*
X-981315Y850320D01*
X-980265Y851820D01*
X-979040Y852820D01*
X-977640Y853070D01*
X-976240Y852820D01*
X-975015Y851820D01*
X-973965Y850320D01*
X-973265Y848570D01*
X-972915Y846570D01*
Y844570D01*
X-973265Y842570D01*
X-973965Y840820D01*
X-975015Y839320D01*
X-976240Y838320D01*
X-977640Y838070D01*
G01X-966940D02*
Y853070D01*
X-962565D01*
X-961165Y852320D01*
X-960290Y851320D01*
X-959940Y849320D01*
X-960290Y847320D01*
X-961340Y846070D01*
X-962565Y845320D01*
X-966940D01*
G01X-962565D02*
X-959940Y838070D01*
G01X-939415D02*
X-935040Y853070D01*
X-930665Y838070D01*
G01X-932240Y843320D02*
X-937840D01*
G01X-924340Y853070D02*
Y838070D01*
X-917340D01*
G01X-910140Y853070D02*
Y838070D01*
X-903140D01*
G01X-881740D02*
Y853070D01*
X-877540D01*
X-876140Y852320D01*
X-875090Y850570D01*
X-874740Y848570D01*
X-875090Y846570D01*
X-875965Y845070D01*
X-877540Y844320D01*
X-881740D01*
G01X-860190Y851820D02*
X-861240Y852570D01*
X-862465Y853070D01*
X-863865D01*
X-865440Y852320D01*
X-866665Y851070D01*
X-867540Y849570D01*
X-868240Y847070D01*
X-868415Y844820D01*
X-868065Y842570D01*
X-867540Y841070D01*
X-866490Y839570D01*
X-865265Y838570D01*
X-864040Y838070D01*
X-862815D01*
X-861590Y838570D01*
X-860540Y839320D01*
X-859665Y840320D01*
G01X-848440Y846070D02*
X-847740Y846820D01*
X-847215Y848070D01*
X-846865Y849820D01*
X-847215Y851320D01*
X-847915Y852320D01*
X-849140Y853070D01*
X-853865D01*
Y838070D01*
X-848090D01*
X-846865Y839070D01*
X-846165Y840570D01*
X-845815Y842320D01*
X-846165Y844070D01*
X-847215Y845570D01*
X-848440Y846070D01*
X-853865D01*
G01X-840015Y838070D02*
X-835640Y853070D01*
X-831265Y838070D01*
G01X-832840Y843320D02*
X-838440D01*
G01X-810740Y838070D02*
Y853070D01*
X-806365D01*
X-804965Y852320D01*
X-804090Y851320D01*
X-803740Y849320D01*
X-804090Y847320D01*
X-805140Y846070D01*
X-806365Y845320D01*
X-810740D01*
G01X-806365D02*
X-803740Y838070D01*
G01X-789540D02*
X-796540D01*
Y853070D01*
X-789540D01*
G01X-792340Y845820D02*
X-796540D01*
G01X-784090Y853070D02*
X-781640Y838070D01*
X-778840Y853070D01*
X-776040Y838070D01*
X-773590Y853070D01*
G01X-764640Y838070D02*
X-766040Y838320D01*
X-767265Y839320D01*
X-768315Y840820D01*
X-769015Y842570D01*
X-769365Y844570D01*
Y846570D01*
X-769015Y848570D01*
X-768315Y850320D01*
X-767265Y851820D01*
X-766040Y852820D01*
X-764640Y853070D01*
X-763240Y852820D01*
X-762015Y851820D01*
X-760965Y850320D01*
X-760265Y848570D01*
X-759915Y846570D01*
Y844570D01*
X-760265Y842570D01*
X-760965Y840820D01*
X-762015Y839320D01*
X-763240Y838320D01*
X-764640Y838070D01*
G01X-753940D02*
Y853070D01*
X-749565D01*
X-748165Y852320D01*
X-747290Y851320D01*
X-746940Y849320D01*
X-747290Y847320D01*
X-748340Y846070D01*
X-749565Y845320D01*
X-753940D01*
G01X-749565D02*
X-746940Y838070D01*
G01X-740090D02*
Y853070D01*
G01X-733440D02*
X-740090Y843820D01*
G01X-732390Y838070D02*
X-737115Y848070D01*
G01X-722040Y837570D02*
X-722390Y837820D01*
Y838320D01*
X-722040Y838570D01*
X-721690Y838320D01*
Y837820D01*
X-722040Y837570D01*
G01X-1499190Y886820D02*
X-1500240Y887570D01*
X-1501465Y888070D01*
X-1502865D01*
X-1504440Y887320D01*
X-1505665Y886070D01*
X-1506540Y884570D01*
X-1507240Y882070D01*
X-1507415Y879820D01*
X-1507065Y877570D01*
X-1506540Y876070D01*
X-1505490Y874570D01*
X-1504265Y873570D01*
X-1503040Y873070D01*
X-1501815D01*
X-1500590Y873570D01*
X-1499540Y874320D01*
X-1498665Y875320D01*
G01X-1488840Y873070D02*
X-1490240Y873320D01*
X-1491465Y874320D01*
X-1492515Y875820D01*
X-1493215Y877570D01*
X-1493565Y879570D01*
Y881570D01*
X-1493215Y883570D01*
X-1492515Y885320D01*
X-1491465Y886820D01*
X-1490240Y887820D01*
X-1488840Y888070D01*
X-1487440Y887820D01*
X-1486215Y886820D01*
X-1485165Y885320D01*
X-1484465Y883570D01*
X-1484115Y881570D01*
Y879570D01*
X-1484465Y877570D01*
X-1485165Y875820D01*
X-1486215Y874320D01*
X-1487440Y873320D01*
X-1488840Y873070D01*
G01X-1478665D02*
Y888070D01*
X-1470615Y873070D01*
Y888070D01*
G01X-1464115Y875070D02*
X-1462715Y873820D01*
X-1461140Y873070D01*
X-1459740D01*
X-1458340Y873820D01*
X-1457290Y875070D01*
X-1456765Y876820D01*
X-1457115Y878570D01*
X-1457990Y880070D01*
X-1459565Y881070D01*
X-1461665Y881570D01*
X-1462890Y882570D01*
X-1463415Y884320D01*
X-1463065Y886070D01*
X-1462190Y887320D01*
X-1460965Y888070D01*
X-1459740D01*
X-1458515Y887570D01*
X-1457465Y886320D01*
G01X-1448340Y888070D02*
X-1444140D01*
G01X-1446240D02*
Y873070D01*
G01X-1448340D02*
X-1444140D01*
G01X-1435890D02*
Y888070D01*
X-1432390D01*
X-1430990Y887320D01*
X-1429940Y886320D01*
X-1429065Y884820D01*
X-1428365Y883070D01*
X-1428190Y880570D01*
X-1428365Y878070D01*
X-1429065Y876320D01*
X-1429940Y874820D01*
X-1430990Y873820D01*
X-1432390Y873070D01*
X-1435890D01*
G01X-1414340D02*
X-1421340D01*
Y888070D01*
X-1414340D01*
G01X-1417140Y880820D02*
X-1421340D01*
G01X-1407140Y873070D02*
Y888070D01*
X-1402765D01*
X-1401365Y887320D01*
X-1400490Y886320D01*
X-1400140Y884320D01*
X-1400490Y882320D01*
X-1401540Y881070D01*
X-1402765Y880320D01*
X-1407140D01*
G01X-1402765D02*
X-1400140Y873070D01*
G01X-1385940D02*
X-1392940D01*
Y888070D01*
X-1385940D01*
G01X-1388740Y880820D02*
X-1392940D01*
G01X-1379090Y873070D02*
Y888070D01*
X-1375590D01*
X-1374190Y887320D01*
X-1373140Y886320D01*
X-1372265Y884820D01*
X-1371565Y883070D01*
X-1371390Y880570D01*
X-1371565Y878070D01*
X-1372265Y876320D01*
X-1373140Y874820D01*
X-1374190Y873820D01*
X-1375590Y873070D01*
X-1379090D01*
G01X-1351390D02*
Y888070D01*
X-1346840Y875570D01*
X-1342290Y888070D01*
Y873070D01*
G01X-1336315Y875070D02*
X-1334915Y873820D01*
X-1333340Y873070D01*
X-1331940D01*
X-1330540Y873820D01*
X-1329490Y875070D01*
X-1328965Y876820D01*
X-1329315Y878570D01*
X-1330190Y880070D01*
X-1331765Y881070D01*
X-1333865Y881570D01*
X-1335090Y882570D01*
X-1335615Y884320D01*
X-1335265Y886070D01*
X-1334390Y887320D01*
X-1333165Y888070D01*
X-1331940D01*
X-1330715Y887570D01*
X-1329665Y886320D01*
G01X-1322290Y873070D02*
Y888070D01*
X-1318790D01*
X-1317390Y887320D01*
X-1316340Y886320D01*
X-1315465Y884820D01*
X-1314765Y883070D01*
X-1314590Y880570D01*
X-1314765Y878070D01*
X-1315465Y876320D01*
X-1316340Y874820D01*
X-1317390Y873820D01*
X-1318790Y873070D01*
X-1322290D01*
G01X-1293540Y888070D02*
Y873070D01*
X-1286540D01*
G01X-1272340D02*
X-1279340D01*
Y888070D01*
X-1272340D01*
G01X-1275140Y880820D02*
X-1279340D01*
G01X-1266015Y888070D02*
X-1261640Y873070D01*
X-1257265Y888070D01*
G01X-1243940Y873070D02*
X-1250940D01*
Y888070D01*
X-1243940D01*
G01X-1246740Y880820D02*
X-1250940D01*
G01X-1236740Y888070D02*
Y873070D01*
X-1229740D01*
G01X-1208165Y879320D02*
X-1206940Y881070D01*
X-1205890Y882070D01*
X-1204490Y882570D01*
X-1203265Y882070D01*
X-1202390Y881070D01*
X-1201690Y879570D01*
X-1201515Y877820D01*
X-1201690Y876320D01*
X-1202390Y874820D01*
X-1203440Y873570D01*
X-1204665Y873070D01*
X-1206065Y873570D01*
X-1207290Y875070D01*
X-1207990Y877320D01*
X-1208165Y879820D01*
X-1207815Y883070D01*
X-1207290Y884820D01*
X-1206415Y886570D01*
X-1205190Y887820D01*
X-1203965Y888070D01*
X-1202740Y887570D01*
X-1201865Y886320D01*
G01X-1180815Y873070D02*
X-1176440Y888070D01*
X-1172065Y873070D01*
G01X-1173640Y878320D02*
X-1179240D01*
G01X-1166265Y873070D02*
Y888070D01*
X-1158215Y873070D01*
Y888070D01*
G01X-1151890Y873070D02*
Y888070D01*
X-1148390D01*
X-1146990Y887320D01*
X-1145940Y886320D01*
X-1145065Y884820D01*
X-1144365Y883070D01*
X-1144190Y880570D01*
X-1144365Y878070D01*
X-1145065Y876320D01*
X-1145940Y874820D01*
X-1146990Y873820D01*
X-1148390Y873070D01*
X-1151890D01*
G01X-1123490Y888070D02*
Y877320D01*
X-1122790Y875070D01*
X-1121390Y873570D01*
X-1119640Y873070D01*
X-1117890Y873570D01*
X-1116490Y875070D01*
X-1115790Y877320D01*
Y888070D01*
G01X-1109115Y875070D02*
X-1107715Y873820D01*
X-1106140Y873070D01*
X-1104740D01*
X-1103340Y873820D01*
X-1102290Y875070D01*
X-1101765Y876820D01*
X-1102115Y878570D01*
X-1102990Y880070D01*
X-1104565Y881070D01*
X-1106665Y881570D01*
X-1107890Y882570D01*
X-1108415Y884320D01*
X-1108065Y886070D01*
X-1107190Y887320D01*
X-1105965Y888070D01*
X-1104740D01*
X-1103515Y887570D01*
X-1102465Y886320D01*
G01X-1087740Y873070D02*
X-1094740D01*
Y888070D01*
X-1087740D01*
G01X-1090540Y880820D02*
X-1094740D01*
G01X-1059340Y873070D02*
X-1066340D01*
Y888070D01*
X-1059340D01*
G01X-1062140Y880820D02*
X-1066340D01*
G01X-1050740Y888070D02*
X-1046540D01*
G01X-1048640D02*
Y873070D01*
G01X-1050740D02*
X-1046540D01*
G01X-1038815D02*
X-1034440Y888070D01*
X-1030065Y873070D01*
G01X-1031640Y878320D02*
X-1037240D01*
G01X-1023390Y872570D02*
X-1017090Y888070D01*
G01X-1009540Y876070D02*
X-1008665Y874570D01*
X-1007615Y873570D01*
X-1006390Y873070D01*
X-1004990Y873570D01*
X-1003940Y874570D01*
X-1002890Y876070D01*
X-1002540Y878070D01*
Y888070D01*
G01X-988340Y873070D02*
X-995340D01*
Y888070D01*
X-988340D01*
G01X-991140Y880820D02*
X-995340D01*
G01X-981140Y873070D02*
Y888070D01*
X-976940D01*
X-975540Y887320D01*
X-974490Y885570D01*
X-974140Y883570D01*
X-974490Y881570D01*
X-975365Y880070D01*
X-976940Y879320D01*
X-981140D01*
G01X-949240Y873070D02*
Y888070D01*
X-951340Y885070D01*
G01Y873070D02*
X-947140D01*
G01X-935040D02*
Y888070D01*
X-937140Y885070D01*
G01Y873070D02*
X-932940D01*
G01X-924690Y876070D02*
X-923640Y874320D01*
X-922240Y873320D01*
X-920665Y873070D01*
X-919265Y873320D01*
X-917865Y874570D01*
X-916990Y876070D01*
X-916815Y877570D01*
X-917165Y879320D01*
X-918390Y880570D01*
X-919615Y881070D01*
X-921190D01*
G01X-919615D02*
X-918565Y881820D01*
X-917690Y883070D01*
X-917340Y884570D01*
X-917690Y886070D01*
X-918565Y887320D01*
X-920140Y888070D01*
X-921715Y887820D01*
X-923290Y886820D01*
G01X-908915Y878070D02*
X-904365D01*
G01X-896815Y873070D02*
X-892440Y888070D01*
X-888065Y873070D01*
G01X-889640Y878320D02*
X-895240D01*
G01X-867365Y873070D02*
Y888070D01*
X-860715D01*
G01X-863165Y880820D02*
X-867365D01*
G01X-849840Y873070D02*
X-851240Y873320D01*
X-852465Y874320D01*
X-853515Y875820D01*
X-854215Y877570D01*
X-854565Y879570D01*
Y881570D01*
X-854215Y883570D01*
X-853515Y885320D01*
X-852465Y886820D01*
X-851240Y887820D01*
X-849840Y888070D01*
X-848440Y887820D01*
X-847215Y886820D01*
X-846165Y885320D01*
X-845465Y883570D01*
X-845115Y881570D01*
Y879570D01*
X-845465Y877570D01*
X-846165Y875820D01*
X-847215Y874320D01*
X-848440Y873320D01*
X-849840Y873070D01*
G01X-839140D02*
Y888070D01*
X-834765D01*
X-833365Y887320D01*
X-832490Y886320D01*
X-832140Y884320D01*
X-832490Y882320D01*
X-833540Y881070D01*
X-834765Y880320D01*
X-839140D01*
G01X-834765D02*
X-832140Y873070D01*
G01X-810915D02*
Y888070D01*
G01X-803565D02*
Y873070D01*
G01Y880570D02*
X-810915D01*
G01X-797415Y873070D02*
X-793040Y888070D01*
X-788665Y873070D01*
G01X-790240Y878320D02*
X-795840D01*
G01X-782865Y873070D02*
Y888070D01*
X-774815Y873070D01*
Y888070D01*
G01X-768490Y873070D02*
Y888070D01*
X-764990D01*
X-763590Y887320D01*
X-762540Y886320D01*
X-761665Y884820D01*
X-760965Y883070D01*
X-760790Y880570D01*
X-760965Y878070D01*
X-761665Y876320D01*
X-762540Y874820D01*
X-763590Y873820D01*
X-764990Y873070D01*
X-768490D01*
G01X-753940Y888070D02*
Y873070D01*
X-746940D01*
G01X-738340Y888070D02*
X-734140D01*
G01X-736240D02*
Y873070D01*
G01X-738340D02*
X-734140D01*
G01X-726065D02*
Y888070D01*
X-718015Y873070D01*
Y888070D01*
G01X-706790Y880570D02*
X-703290D01*
Y876070D01*
X-704340Y874570D01*
X-705565Y873570D01*
X-707315Y873070D01*
X-709065Y873570D01*
X-710290Y874570D01*
X-711340Y876070D01*
X-712040Y877820D01*
X-712390Y879820D01*
Y881570D01*
X-712040Y883070D01*
X-711340Y884820D01*
X-710290Y886320D01*
X-709240Y887320D01*
X-707840Y888070D01*
X-706615D01*
X-705215Y887570D01*
X-704165Y886570D01*
G01X-693640Y872570D02*
X-693990Y872820D01*
Y873320D01*
X-693640Y873570D01*
X-693290Y873320D01*
Y872820D01*
X-693640Y872570D01*
G01X-1506540Y918070D02*
Y903070D01*
X-1499540D01*
G01X-1485340D02*
X-1492340D01*
Y918070D01*
X-1485340D01*
G01X-1488140Y910820D02*
X-1492340D01*
G01X-1473590Y910570D02*
X-1470090D01*
Y906070D01*
X-1471140Y904570D01*
X-1472365Y903570D01*
X-1474115Y903070D01*
X-1475865Y903570D01*
X-1477090Y904570D01*
X-1478140Y906070D01*
X-1478840Y907820D01*
X-1479190Y909820D01*
Y911570D01*
X-1478840Y913070D01*
X-1478140Y914820D01*
X-1477090Y916320D01*
X-1476040Y917320D01*
X-1474640Y918070D01*
X-1473415D01*
X-1472015Y917570D01*
X-1470965Y916570D01*
G01X-1462540Y918070D02*
X-1458340D01*
G01X-1460440D02*
Y903070D01*
G01X-1462540D02*
X-1458340D01*
G01X-1444840Y911070D02*
X-1444140Y911820D01*
X-1443615Y913070D01*
X-1443265Y914820D01*
X-1443615Y916320D01*
X-1444315Y917320D01*
X-1445540Y918070D01*
X-1450265D01*
Y903070D01*
X-1444490D01*
X-1443265Y904070D01*
X-1442565Y905570D01*
X-1442215Y907320D01*
X-1442565Y909070D01*
X-1443615Y910570D01*
X-1444840Y911070D01*
X-1450265D01*
G01X-1435540Y918070D02*
Y903070D01*
X-1428540D01*
G01X-1414340D02*
X-1421340D01*
Y918070D01*
X-1414340D01*
G01X-1417140Y910820D02*
X-1421340D01*
G01X-1389440Y918070D02*
Y903070D01*
G01X-1393465Y918070D02*
X-1385415D01*
G01X-1378915Y903070D02*
Y918070D01*
G01X-1371565D02*
Y903070D01*
G01Y910570D02*
X-1378915D01*
G01X-1357540Y903070D02*
X-1364540D01*
Y918070D01*
X-1357540D01*
G01X-1360340Y910820D02*
X-1364540D01*
G01X-1350865Y903070D02*
Y918070D01*
X-1342815Y903070D01*
Y918070D01*
G01X-1322815Y903070D02*
X-1318440Y918070D01*
X-1314065Y903070D01*
G01X-1315640Y908320D02*
X-1321240D01*
G01X-1307740Y918070D02*
Y903070D01*
X-1300740D01*
G01X-1293540Y918070D02*
Y903070D01*
X-1286540D01*
G01X-1265140D02*
Y918070D01*
X-1260940D01*
X-1259540Y917320D01*
X-1258490Y915570D01*
X-1258140Y913570D01*
X-1258490Y911570D01*
X-1259365Y910070D01*
X-1260940Y909320D01*
X-1265140D01*
G01X-1250940Y918070D02*
Y903070D01*
X-1243940D01*
G01X-1237615D02*
X-1233240Y918070D01*
X-1228865Y903070D01*
G01X-1230440Y908320D02*
X-1236040D01*
G01X-1222715Y905070D02*
X-1221315Y903820D01*
X-1219740Y903070D01*
X-1218340D01*
X-1216940Y903820D01*
X-1215890Y905070D01*
X-1215365Y906820D01*
X-1215715Y908570D01*
X-1216590Y910070D01*
X-1218165Y911070D01*
X-1220265Y911570D01*
X-1221490Y912570D01*
X-1222015Y914320D01*
X-1221665Y916070D01*
X-1220790Y917320D01*
X-1219565Y918070D01*
X-1218340D01*
X-1217115Y917570D01*
X-1216065Y916320D01*
G01X-1204840Y918070D02*
Y903070D01*
G01X-1208865Y918070D02*
X-1200815D01*
G01X-1192740D02*
X-1188540D01*
G01X-1190640D02*
Y903070D01*
G01X-1192740D02*
X-1188540D01*
G01X-1172590Y916820D02*
X-1173640Y917570D01*
X-1174865Y918070D01*
X-1176265D01*
X-1177840Y917320D01*
X-1179065Y916070D01*
X-1179940Y914570D01*
X-1180640Y912070D01*
X-1180815Y909820D01*
X-1180465Y907570D01*
X-1179940Y906070D01*
X-1178890Y904570D01*
X-1177665Y903570D01*
X-1176440Y903070D01*
X-1175215D01*
X-1173990Y903570D01*
X-1172940Y904320D01*
X-1172065Y905320D01*
G01X-1151540Y903070D02*
Y918070D01*
X-1147340D01*
X-1145940Y917320D01*
X-1144890Y915570D01*
X-1144540Y913570D01*
X-1144890Y911570D01*
X-1145765Y910070D01*
X-1147340Y909320D01*
X-1151540D01*
G01X-1138215Y903070D02*
X-1133840Y918070D01*
X-1129465Y903070D01*
G01X-1131040Y908320D02*
X-1136640D01*
G01X-1115790Y916820D02*
X-1116840Y917570D01*
X-1118065Y918070D01*
X-1119465D01*
X-1121040Y917320D01*
X-1122265Y916070D01*
X-1123140Y914570D01*
X-1123840Y912070D01*
X-1124015Y909820D01*
X-1123665Y907570D01*
X-1123140Y906070D01*
X-1122090Y904570D01*
X-1120865Y903570D01*
X-1119640Y903070D01*
X-1118415D01*
X-1117190Y903570D01*
X-1116140Y904320D01*
X-1115265Y905320D01*
G01X-1109290Y903070D02*
Y918070D01*
G01X-1102640D02*
X-1109290Y908820D01*
G01X-1101590Y903070D02*
X-1106315Y913070D01*
G01X-1095615Y903070D02*
X-1091240Y918070D01*
X-1086865Y903070D01*
G01X-1088440Y908320D02*
X-1094040D01*
G01X-1075990Y910570D02*
X-1072490D01*
Y906070D01*
X-1073540Y904570D01*
X-1074765Y903570D01*
X-1076515Y903070D01*
X-1078265Y903570D01*
X-1079490Y904570D01*
X-1080540Y906070D01*
X-1081240Y907820D01*
X-1081590Y909820D01*
Y911570D01*
X-1081240Y913070D01*
X-1080540Y914820D01*
X-1079490Y916320D01*
X-1078440Y917320D01*
X-1077040Y918070D01*
X-1075815D01*
X-1074415Y917570D01*
X-1073365Y916570D01*
G01X-1059340Y903070D02*
X-1066340D01*
Y918070D01*
X-1059340D01*
G01X-1062140Y910820D02*
X-1066340D01*
G01X-1052490Y903070D02*
Y918070D01*
X-1048990D01*
X-1047590Y917320D01*
X-1046540Y916320D01*
X-1045665Y914820D01*
X-1044965Y913070D01*
X-1044790Y910570D01*
X-1044965Y908070D01*
X-1045665Y906320D01*
X-1046540Y904820D01*
X-1047590Y903820D01*
X-1048990Y903070D01*
X-1052490D01*
G01X-1016390Y916820D02*
X-1017440Y917570D01*
X-1018665Y918070D01*
X-1020065D01*
X-1021640Y917320D01*
X-1022865Y916070D01*
X-1023740Y914570D01*
X-1024440Y912070D01*
X-1024615Y909820D01*
X-1024265Y907570D01*
X-1023740Y906070D01*
X-1022690Y904570D01*
X-1021465Y903570D01*
X-1020240Y903070D01*
X-1019015D01*
X-1017790Y903570D01*
X-1016740Y904320D01*
X-1015865Y905320D01*
G01X-1006040Y903070D02*
X-1007440Y903320D01*
X-1008665Y904320D01*
X-1009715Y905820D01*
X-1010415Y907570D01*
X-1010765Y909570D01*
Y911570D01*
X-1010415Y913570D01*
X-1009715Y915320D01*
X-1008665Y916820D01*
X-1007440Y917820D01*
X-1006040Y918070D01*
X-1004640Y917820D01*
X-1003415Y916820D01*
X-1002365Y915320D01*
X-1001665Y913570D01*
X-1001315Y911570D01*
Y909570D01*
X-1001665Y907570D01*
X-1002365Y905820D01*
X-1003415Y904320D01*
X-1004640Y903320D01*
X-1006040Y903070D01*
G01X-996390D02*
Y918070D01*
X-991840Y905570D01*
X-987290Y918070D01*
Y903070D01*
G01X-981140D02*
Y918070D01*
X-976940D01*
X-975540Y917320D01*
X-974490Y915570D01*
X-974140Y913570D01*
X-974490Y911570D01*
X-975365Y910070D01*
X-976940Y909320D01*
X-981140D01*
G01X-963440Y903070D02*
X-964840Y903320D01*
X-966065Y904320D01*
X-967115Y905820D01*
X-967815Y907570D01*
X-968165Y909570D01*
Y911570D01*
X-967815Y913570D01*
X-967115Y915320D01*
X-966065Y916820D01*
X-964840Y917820D01*
X-963440Y918070D01*
X-962040Y917820D01*
X-960815Y916820D01*
X-959765Y915320D01*
X-959065Y913570D01*
X-958715Y911570D01*
Y909570D01*
X-959065Y907570D01*
X-959765Y905820D01*
X-960815Y904320D01*
X-962040Y903320D01*
X-963440Y903070D01*
G01X-953265D02*
Y918070D01*
X-945215Y903070D01*
Y918070D01*
G01X-931540Y903070D02*
X-938540D01*
Y918070D01*
X-931540D01*
G01X-934340Y910820D02*
X-938540D01*
G01X-924865Y903070D02*
Y918070D01*
X-916815Y903070D01*
Y918070D01*
G01X-906640D02*
Y903070D01*
G01X-910665Y918070D02*
X-902615D01*
G01X-896115Y905070D02*
X-894715Y903820D01*
X-893140Y903070D01*
X-891740D01*
X-890340Y903820D01*
X-889290Y905070D01*
X-888765Y906820D01*
X-889115Y908570D01*
X-889990Y910070D01*
X-891565Y911070D01*
X-893665Y911570D01*
X-894890Y912570D01*
X-895415Y914320D01*
X-895065Y916070D01*
X-894190Y917320D01*
X-892965Y918070D01*
X-891740D01*
X-890515Y917570D01*
X-889465Y916320D01*
G01X-868415Y903070D02*
X-864040Y918070D01*
X-859665Y903070D01*
G01X-861240Y908320D02*
X-866840D01*
G01X-853340Y903070D02*
Y918070D01*
X-848965D01*
X-847565Y917320D01*
X-846690Y916320D01*
X-846340Y914320D01*
X-846690Y912320D01*
X-847740Y911070D01*
X-848965Y910320D01*
X-853340D01*
G01X-848965D02*
X-846340Y903070D01*
G01X-832140D02*
X-839140D01*
Y918070D01*
X-832140D01*
G01X-834940Y910820D02*
X-839140D01*
G01X-807240Y918070D02*
Y903070D01*
G01X-811265Y918070D02*
X-803215D01*
G01X-793040Y903070D02*
X-794440Y903320D01*
X-795665Y904320D01*
X-796715Y905820D01*
X-797415Y907570D01*
X-797765Y909570D01*
Y911570D01*
X-797415Y913570D01*
X-796715Y915320D01*
X-795665Y916820D01*
X-794440Y917820D01*
X-793040Y918070D01*
X-791640Y917820D01*
X-790415Y916820D01*
X-789365Y915320D01*
X-788665Y913570D01*
X-788315Y911570D01*
Y909570D01*
X-788665Y907570D01*
X-789365Y905820D01*
X-790415Y904320D01*
X-791640Y903320D01*
X-793040Y903070D01*
G01X-763240Y911070D02*
X-762540Y911820D01*
X-762015Y913070D01*
X-761665Y914820D01*
X-762015Y916320D01*
X-762715Y917320D01*
X-763940Y918070D01*
X-768665D01*
Y903070D01*
X-762890D01*
X-761665Y904070D01*
X-760965Y905570D01*
X-760615Y907320D01*
X-760965Y909070D01*
X-762015Y910570D01*
X-763240Y911070D01*
X-768665D01*
G01X-746940Y903070D02*
X-753940D01*
Y918070D01*
X-746940D01*
G01X-749740Y910820D02*
X-753940D01*
G01X-1499190Y946820D02*
X-1500240Y947570D01*
X-1501465Y948070D01*
X-1502865D01*
X-1504440Y947320D01*
X-1505665Y946070D01*
X-1506540Y944570D01*
X-1507240Y942070D01*
X-1507415Y939820D01*
X-1507065Y937570D01*
X-1506540Y936070D01*
X-1505490Y934570D01*
X-1504265Y933570D01*
X-1503040Y933070D01*
X-1501815D01*
X-1500590Y933570D01*
X-1499540Y934320D01*
X-1498665Y935320D01*
G01X-1493215Y933070D02*
X-1488840Y948070D01*
X-1484465Y933070D01*
G01X-1486040Y938320D02*
X-1491640D01*
G01X-1478140Y948070D02*
Y933070D01*
X-1471140D01*
G01X-1463940Y948070D02*
Y933070D01*
X-1456940D01*
G01X-1446240D02*
X-1447640Y933320D01*
X-1448865Y934320D01*
X-1449915Y935820D01*
X-1450615Y937570D01*
X-1450965Y939570D01*
Y941570D01*
X-1450615Y943570D01*
X-1449915Y945320D01*
X-1448865Y946820D01*
X-1447640Y947820D01*
X-1446240Y948070D01*
X-1444840Y947820D01*
X-1443615Y946820D01*
X-1442565Y945320D01*
X-1441865Y943570D01*
X-1441515Y941570D01*
Y939570D01*
X-1441865Y937570D01*
X-1442565Y935820D01*
X-1443615Y934320D01*
X-1444840Y933320D01*
X-1446240Y933070D01*
G01X-1435890Y948070D02*
Y937320D01*
X-1435190Y935070D01*
X-1433790Y933570D01*
X-1432040Y933070D01*
X-1430290Y933570D01*
X-1428890Y935070D01*
X-1428190Y937320D01*
Y948070D01*
G01X-1417840D02*
Y933070D01*
G01X-1421865Y948070D02*
X-1413815D01*
G01X-1389440Y933070D02*
X-1390840Y933320D01*
X-1392065Y934320D01*
X-1393115Y935820D01*
X-1393815Y937570D01*
X-1394165Y939570D01*
Y941570D01*
X-1393815Y943570D01*
X-1393115Y945320D01*
X-1392065Y946820D01*
X-1390840Y947820D01*
X-1389440Y948070D01*
X-1388040Y947820D01*
X-1386815Y946820D01*
X-1385765Y945320D01*
X-1385065Y943570D01*
X-1384715Y941570D01*
Y939570D01*
X-1385065Y937570D01*
X-1385765Y935820D01*
X-1386815Y934320D01*
X-1388040Y933320D01*
X-1389440Y933070D01*
G01X-1379265D02*
Y948070D01*
X-1371215Y933070D01*
Y948070D01*
G01X-1351390Y933070D02*
Y948070D01*
X-1346840Y935570D01*
X-1342290Y948070D01*
Y933070D01*
G01X-1336315Y935070D02*
X-1334915Y933820D01*
X-1333340Y933070D01*
X-1331940D01*
X-1330540Y933820D01*
X-1329490Y935070D01*
X-1328965Y936820D01*
X-1329315Y938570D01*
X-1330190Y940070D01*
X-1331765Y941070D01*
X-1333865Y941570D01*
X-1335090Y942570D01*
X-1335615Y944320D01*
X-1335265Y946070D01*
X-1334390Y947320D01*
X-1333165Y948070D01*
X-1331940D01*
X-1330715Y947570D01*
X-1329665Y946320D01*
G01X-1322290Y933070D02*
Y948070D01*
X-1318790D01*
X-1317390Y947320D01*
X-1316340Y946320D01*
X-1315465Y944820D01*
X-1314765Y943070D01*
X-1314590Y940570D01*
X-1314765Y938070D01*
X-1315465Y936320D01*
X-1316340Y934820D01*
X-1317390Y933820D01*
X-1318790Y933070D01*
X-1322290D01*
G01X-1293540Y948070D02*
Y933070D01*
X-1286540D01*
G01X-1280215D02*
X-1275840Y948070D01*
X-1271465Y933070D01*
G01X-1273040Y938320D02*
X-1278640D01*
G01X-1260240Y941070D02*
X-1259540Y941820D01*
X-1259015Y943070D01*
X-1258665Y944820D01*
X-1259015Y946320D01*
X-1259715Y947320D01*
X-1260940Y948070D01*
X-1265665D01*
Y933070D01*
X-1259890D01*
X-1258665Y934070D01*
X-1257965Y935570D01*
X-1257615Y937320D01*
X-1257965Y939070D01*
X-1259015Y940570D01*
X-1260240Y941070D01*
X-1265665D01*
G01X-1243940Y933070D02*
X-1250940D01*
Y948070D01*
X-1243940D01*
G01X-1246740Y940820D02*
X-1250940D01*
G01X-1236740Y948070D02*
Y933070D01*
X-1229740D01*
G01X-1219040Y932570D02*
X-1219390Y932820D01*
Y933320D01*
X-1219040Y933570D01*
X-1218690Y933320D01*
Y932820D01*
X-1219040Y932570D01*
G01X-1192740Y948070D02*
X-1188540D01*
G01X-1190640D02*
Y933070D01*
G01X-1192740D02*
X-1188540D01*
G01X-1179765D02*
Y948070D01*
X-1173115D01*
G01X-1175565Y940820D02*
X-1179765D01*
G01X-1152590Y933070D02*
Y948070D01*
X-1148040Y935570D01*
X-1143490Y948070D01*
Y933070D01*
G01X-1137515Y935070D02*
X-1136115Y933820D01*
X-1134540Y933070D01*
X-1133140D01*
X-1131740Y933820D01*
X-1130690Y935070D01*
X-1130165Y936820D01*
X-1130515Y938570D01*
X-1131390Y940070D01*
X-1132965Y941070D01*
X-1135065Y941570D01*
X-1136290Y942570D01*
X-1136815Y944320D01*
X-1136465Y946070D01*
X-1135590Y947320D01*
X-1134365Y948070D01*
X-1133140D01*
X-1131915Y947570D01*
X-1130865Y946320D01*
G01X-1123490Y933070D02*
Y948070D01*
X-1119990D01*
X-1118590Y947320D01*
X-1117540Y946320D01*
X-1116665Y944820D01*
X-1115965Y943070D01*
X-1115790Y940570D01*
X-1115965Y938070D01*
X-1116665Y936320D01*
X-1117540Y934820D01*
X-1118590Y933820D01*
X-1119990Y933070D01*
X-1123490D01*
G01X-1094740Y948070D02*
Y933070D01*
X-1087740D01*
G01X-1081415D02*
X-1077040Y948070D01*
X-1072665Y933070D01*
G01X-1074240Y938320D02*
X-1079840D01*
G01X-1061440Y941070D02*
X-1060740Y941820D01*
X-1060215Y943070D01*
X-1059865Y944820D01*
X-1060215Y946320D01*
X-1060915Y947320D01*
X-1062140Y948070D01*
X-1066865D01*
Y933070D01*
X-1061090D01*
X-1059865Y934070D01*
X-1059165Y935570D01*
X-1058815Y937320D01*
X-1059165Y939070D01*
X-1060215Y940570D01*
X-1061440Y941070D01*
X-1066865D01*
G01X-1045140Y933070D02*
X-1052140D01*
Y948070D01*
X-1045140D01*
G01X-1047940Y940820D02*
X-1052140D01*
G01X-1037940Y948070D02*
Y933070D01*
X-1030940D01*
G01X-1008140Y948070D02*
X-1003940D01*
G01X-1006040D02*
Y933070D01*
G01X-1008140D02*
X-1003940D01*
G01X-995515Y935070D02*
X-994115Y933820D01*
X-992540Y933070D01*
X-991140D01*
X-989740Y933820D01*
X-988690Y935070D01*
X-988165Y936820D01*
X-988515Y938570D01*
X-989390Y940070D01*
X-990965Y941070D01*
X-993065Y941570D01*
X-994290Y942570D01*
X-994815Y944320D01*
X-994465Y946070D01*
X-993590Y947320D01*
X-992365Y948070D01*
X-991140D01*
X-989915Y947570D01*
X-988865Y946320D01*
G01X-967990Y933070D02*
Y948070D01*
X-963440Y935570D01*
X-958890Y948070D01*
Y933070D01*
G01X-951340Y948070D02*
X-947140D01*
G01X-949240D02*
Y933070D01*
G01X-951340D02*
X-947140D01*
G01X-938715Y935070D02*
X-937315Y933820D01*
X-935740Y933070D01*
X-934340D01*
X-932940Y933820D01*
X-931890Y935070D01*
X-931365Y936820D01*
X-931715Y938570D01*
X-932590Y940070D01*
X-934165Y941070D01*
X-936265Y941570D01*
X-937490Y942570D01*
X-938015Y944320D01*
X-937665Y946070D01*
X-936790Y947320D01*
X-935565Y948070D01*
X-934340D01*
X-933115Y947570D01*
X-932065Y946320D01*
G01X-924515Y935070D02*
X-923115Y933820D01*
X-921540Y933070D01*
X-920140D01*
X-918740Y933820D01*
X-917690Y935070D01*
X-917165Y936820D01*
X-917515Y938570D01*
X-918390Y940070D01*
X-919965Y941070D01*
X-922065Y941570D01*
X-923290Y942570D01*
X-923815Y944320D01*
X-923465Y946070D01*
X-922590Y947320D01*
X-921365Y948070D01*
X-920140D01*
X-918915Y947570D01*
X-917865Y946320D01*
G01X-908740Y948070D02*
X-904540D01*
G01X-906640D02*
Y933070D01*
G01X-908740D02*
X-904540D01*
G01X-896465D02*
Y948070D01*
X-888415Y933070D01*
Y948070D01*
G01X-877190Y940570D02*
X-873690D01*
Y936070D01*
X-874740Y934570D01*
X-875965Y933570D01*
X-877715Y933070D01*
X-879465Y933570D01*
X-880690Y934570D01*
X-881740Y936070D01*
X-882440Y937820D01*
X-882790Y939820D01*
Y941570D01*
X-882440Y943070D01*
X-881740Y944820D01*
X-880690Y946320D01*
X-879640Y947320D01*
X-878240Y948070D01*
X-877015D01*
X-875615Y947570D01*
X-874565Y946570D01*
G01X-849840Y933070D02*
X-851240Y933320D01*
X-852465Y934320D01*
X-853515Y935820D01*
X-854215Y937570D01*
X-854565Y939570D01*
Y941570D01*
X-854215Y943570D01*
X-853515Y945320D01*
X-852465Y946820D01*
X-851240Y947820D01*
X-849840Y948070D01*
X-848440Y947820D01*
X-847215Y946820D01*
X-846165Y945320D01*
X-845465Y943570D01*
X-845115Y941570D01*
Y939570D01*
X-845465Y937570D01*
X-846165Y935820D01*
X-847215Y934320D01*
X-848440Y933320D01*
X-849840Y933070D01*
G01X-839140D02*
Y948070D01*
X-834765D01*
X-833365Y947320D01*
X-832490Y946320D01*
X-832140Y944320D01*
X-832490Y942320D01*
X-833540Y941070D01*
X-834765Y940320D01*
X-839140D01*
G01X-834765D02*
X-832140Y933070D01*
G01X-811265D02*
Y948070D01*
X-803215Y933070D01*
Y948070D01*
G01X-793040Y933070D02*
X-794440Y933320D01*
X-795665Y934320D01*
X-796715Y935820D01*
X-797415Y937570D01*
X-797765Y939570D01*
Y941570D01*
X-797415Y943570D01*
X-796715Y945320D01*
X-795665Y946820D01*
X-794440Y947820D01*
X-793040Y948070D01*
X-791640Y947820D01*
X-790415Y946820D01*
X-789365Y945320D01*
X-788665Y943570D01*
X-788315Y941570D01*
Y939570D01*
X-788665Y937570D01*
X-789365Y935820D01*
X-790415Y934320D01*
X-791640Y933320D01*
X-793040Y933070D01*
G01X-778840Y948070D02*
Y933070D01*
G01X-782865Y948070D02*
X-774815D01*
G01X-1548965Y975570D02*
X-1547915Y977070D01*
X-1546690Y977820D01*
X-1545290Y978070D01*
X-1543540Y977570D01*
X-1542315Y976320D01*
X-1541965Y974820D01*
X-1542140Y973320D01*
X-1542840Y972070D01*
X-1546340Y969570D01*
X-1547915Y967820D01*
X-1548965Y965320D01*
X-1549315Y963070D01*
X-1541965D01*
G01X-1531440Y962570D02*
X-1531790Y962820D01*
Y963320D01*
X-1531440Y963570D01*
X-1531090Y963320D01*
Y962820D01*
X-1531440Y962570D01*
G01X-1506715Y963070D02*
Y978070D01*
G01X-1499365D02*
Y963070D01*
G01Y970570D02*
X-1506715D01*
G01X-1493215Y963070D02*
X-1488840Y978070D01*
X-1484465Y963070D01*
G01X-1486040Y968320D02*
X-1491640D01*
G01X-1478665Y963070D02*
Y978070D01*
X-1470615Y963070D01*
Y978070D01*
G01X-1464290Y963070D02*
Y978070D01*
X-1460790D01*
X-1459390Y977320D01*
X-1458340Y976320D01*
X-1457465Y974820D01*
X-1456765Y973070D01*
X-1456590Y970570D01*
X-1456765Y968070D01*
X-1457465Y966320D01*
X-1458340Y964820D01*
X-1459390Y963820D01*
X-1460790Y963070D01*
X-1464290D01*
G01X-1449740Y978070D02*
Y963070D01*
X-1442740D01*
G01X-1428540D02*
X-1435540D01*
Y978070D01*
X-1428540D01*
G01X-1431340Y970820D02*
X-1435540D01*
G01X-1408190Y963070D02*
Y978070D01*
X-1403640Y965570D01*
X-1399090Y978070D01*
Y963070D01*
G01X-1389440D02*
X-1390840Y963320D01*
X-1392065Y964320D01*
X-1393115Y965820D01*
X-1393815Y967570D01*
X-1394165Y969570D01*
Y971570D01*
X-1393815Y973570D01*
X-1393115Y975320D01*
X-1392065Y976820D01*
X-1390840Y977820D01*
X-1389440Y978070D01*
X-1388040Y977820D01*
X-1386815Y976820D01*
X-1385765Y975320D01*
X-1385065Y973570D01*
X-1384715Y971570D01*
Y969570D01*
X-1385065Y967570D01*
X-1385765Y965820D01*
X-1386815Y964320D01*
X-1388040Y963320D01*
X-1389440Y963070D01*
G01X-1377340Y978070D02*
X-1373140D01*
G01X-1375240D02*
Y963070D01*
G01X-1377340D02*
X-1373140D01*
G01X-1364715Y965070D02*
X-1363315Y963820D01*
X-1361740Y963070D01*
X-1360340D01*
X-1358940Y963820D01*
X-1357890Y965070D01*
X-1357365Y966820D01*
X-1357715Y968570D01*
X-1358590Y970070D01*
X-1360165Y971070D01*
X-1362265Y971570D01*
X-1363490Y972570D01*
X-1364015Y974320D01*
X-1363665Y976070D01*
X-1362790Y977320D01*
X-1361565Y978070D01*
X-1360340D01*
X-1359115Y977570D01*
X-1358065Y976320D01*
G01X-1346840Y978070D02*
Y963070D01*
G01X-1350865Y978070D02*
X-1342815D01*
G01X-1336490D02*
Y967320D01*
X-1335790Y965070D01*
X-1334390Y963570D01*
X-1332640Y963070D01*
X-1330890Y963570D01*
X-1329490Y965070D01*
X-1328790Y967320D01*
Y978070D01*
G01X-1321940Y963070D02*
Y978070D01*
X-1317565D01*
X-1316165Y977320D01*
X-1315290Y976320D01*
X-1314940Y974320D01*
X-1315290Y972320D01*
X-1316340Y971070D01*
X-1317565Y970320D01*
X-1321940D01*
G01X-1317565D02*
X-1314940Y963070D01*
G01X-1300740D02*
X-1307740D01*
Y978070D01*
X-1300740D01*
G01X-1303540Y970820D02*
X-1307740D01*
G01X-1279515Y965070D02*
X-1278115Y963820D01*
X-1276540Y963070D01*
X-1275140D01*
X-1273740Y963820D01*
X-1272690Y965070D01*
X-1272165Y966820D01*
X-1272515Y968570D01*
X-1273390Y970070D01*
X-1274965Y971070D01*
X-1277065Y971570D01*
X-1278290Y972570D01*
X-1278815Y974320D01*
X-1278465Y976070D01*
X-1277590Y977320D01*
X-1276365Y978070D01*
X-1275140D01*
X-1273915Y977570D01*
X-1272865Y976320D01*
G01X-1258140Y963070D02*
X-1265140D01*
Y978070D01*
X-1258140D01*
G01X-1260940Y970820D02*
X-1265140D01*
G01X-1251465Y963070D02*
Y978070D01*
X-1243415Y963070D01*
Y978070D01*
G01X-1236915Y965070D02*
X-1235515Y963820D01*
X-1233940Y963070D01*
X-1232540D01*
X-1231140Y963820D01*
X-1230090Y965070D01*
X-1229565Y966820D01*
X-1229915Y968570D01*
X-1230790Y970070D01*
X-1232365Y971070D01*
X-1234465Y971570D01*
X-1235690Y972570D01*
X-1236215Y974320D01*
X-1235865Y976070D01*
X-1234990Y977320D01*
X-1233765Y978070D01*
X-1232540D01*
X-1231315Y977570D01*
X-1230265Y976320D01*
G01X-1221140Y978070D02*
X-1216940D01*
G01X-1219040D02*
Y963070D01*
G01X-1221140D02*
X-1216940D01*
G01X-1204840Y978070D02*
Y963070D01*
G01X-1208865Y978070D02*
X-1200815D01*
G01X-1192740D02*
X-1188540D01*
G01X-1190640D02*
Y963070D01*
G01X-1192740D02*
X-1188540D01*
G01X-1180815Y978070D02*
X-1176440Y963070D01*
X-1172065Y978070D01*
G01X-1158740Y963070D02*
X-1165740D01*
Y978070D01*
X-1158740D01*
G01X-1161540Y970820D02*
X-1165740D01*
G01X-1137690Y963070D02*
Y978070D01*
X-1134190D01*
X-1132790Y977320D01*
X-1131740Y976320D01*
X-1130865Y974820D01*
X-1130165Y973070D01*
X-1129990Y970570D01*
X-1130165Y968070D01*
X-1130865Y966320D01*
X-1131740Y964820D01*
X-1132790Y963820D01*
X-1134190Y963070D01*
X-1137690D01*
G01X-1116140D02*
X-1123140D01*
Y978070D01*
X-1116140D01*
G01X-1118940Y970820D02*
X-1123140D01*
G01X-1109815Y978070D02*
X-1105440Y963070D01*
X-1101065Y978070D01*
G01X-1093340D02*
X-1089140D01*
G01X-1091240D02*
Y963070D01*
G01X-1093340D02*
X-1089140D01*
G01X-1073190Y976820D02*
X-1074240Y977570D01*
X-1075465Y978070D01*
X-1076865D01*
X-1078440Y977320D01*
X-1079665Y976070D01*
X-1080540Y974570D01*
X-1081240Y972070D01*
X-1081415Y969820D01*
X-1081065Y967570D01*
X-1080540Y966070D01*
X-1079490Y964570D01*
X-1078265Y963570D01*
X-1077040Y963070D01*
X-1075815D01*
X-1074590Y963570D01*
X-1073540Y964320D01*
X-1072665Y965320D01*
G01X-1059340Y963070D02*
X-1066340D01*
Y978070D01*
X-1059340D01*
G01X-1062140Y970820D02*
X-1066340D01*
G01X-1052315Y965070D02*
X-1050915Y963820D01*
X-1049340Y963070D01*
X-1047940D01*
X-1046540Y963820D01*
X-1045490Y965070D01*
X-1044965Y966820D01*
X-1045315Y968570D01*
X-1046190Y970070D01*
X-1047765Y971070D01*
X-1049865Y971570D01*
X-1051090Y972570D01*
X-1051615Y974320D01*
X-1051265Y976070D01*
X-1050390Y977320D01*
X-1049165Y978070D01*
X-1047940D01*
X-1046715Y977570D01*
X-1045665Y976320D01*
G01X-1035315Y958070D02*
X-1037065Y960570D01*
X-1037940Y963070D01*
Y973070D01*
X-1037065Y975570D01*
X-1035315Y978070D01*
G01X-1024790Y963070D02*
Y978070D01*
X-1020240Y965570D01*
X-1015690Y978070D01*
Y963070D01*
G01X-1009715Y965070D02*
X-1008315Y963820D01*
X-1006740Y963070D01*
X-1005340D01*
X-1003940Y963820D01*
X-1002890Y965070D01*
X-1002365Y966820D01*
X-1002715Y968570D01*
X-1003590Y970070D01*
X-1005165Y971070D01*
X-1007265Y971570D01*
X-1008490Y972570D01*
X-1009015Y974320D01*
X-1008665Y976070D01*
X-1007790Y977320D01*
X-1006565Y978070D01*
X-1005340D01*
X-1004115Y977570D01*
X-1003065Y976320D01*
G01X-995690Y963070D02*
Y978070D01*
X-992190D01*
X-990790Y977320D01*
X-989740Y976320D01*
X-988865Y974820D01*
X-988165Y973070D01*
X-987990Y970570D01*
X-988165Y968070D01*
X-988865Y966320D01*
X-989740Y964820D01*
X-990790Y963820D01*
X-992190Y963070D01*
X-995690D01*
G01X-976765Y958070D02*
X-975015Y960570D01*
X-974140Y963070D01*
Y973070D01*
X-975015Y975570D01*
X-976765Y978070D01*
G01X-952740Y963070D02*
Y978070D01*
X-948540D01*
X-947140Y977320D01*
X-946090Y975570D01*
X-945740Y973570D01*
X-946090Y971570D01*
X-946965Y970070D01*
X-948540Y969320D01*
X-952740D01*
G01X-931540Y963070D02*
X-938540D01*
Y978070D01*
X-931540D01*
G01X-934340Y970820D02*
X-938540D01*
G01X-924340Y963070D02*
Y978070D01*
X-919965D01*
X-918565Y977320D01*
X-917690Y976320D01*
X-917340Y974320D01*
X-917690Y972320D01*
X-918740Y971070D01*
X-919965Y970320D01*
X-924340D01*
G01X-919965D02*
X-917340Y963070D01*
G01X-896990D02*
Y978070D01*
X-892440Y965570D01*
X-887890Y978070D01*
Y963070D01*
G01X-882615D02*
X-878240Y978070D01*
X-873865Y963070D01*
G01X-875440Y968320D02*
X-881040D01*
G01X-868065Y963070D02*
Y978070D01*
X-860015Y963070D01*
Y978070D01*
G01X-853690D02*
Y967320D01*
X-852990Y965070D01*
X-851590Y963570D01*
X-849840Y963070D01*
X-848090Y963570D01*
X-846690Y965070D01*
X-845990Y967320D01*
Y978070D01*
G01X-838965Y963070D02*
Y978070D01*
X-832315D01*
G01X-834765Y970820D02*
X-838965D01*
G01X-825815Y963070D02*
X-821440Y978070D01*
X-817065Y963070D01*
G01X-818640Y968320D02*
X-824240D01*
G01X-803390Y976820D02*
X-804440Y977570D01*
X-805665Y978070D01*
X-807065D01*
X-808640Y977320D01*
X-809865Y976070D01*
X-810740Y974570D01*
X-811440Y972070D01*
X-811615Y969820D01*
X-811265Y967570D01*
X-810740Y966070D01*
X-809690Y964570D01*
X-808465Y963570D01*
X-807240Y963070D01*
X-806015D01*
X-804790Y963570D01*
X-803740Y964320D01*
X-802865Y965320D01*
G01X-793040Y978070D02*
Y963070D01*
G01X-797065Y978070D02*
X-789015D01*
G01X-782690D02*
Y967320D01*
X-781990Y965070D01*
X-780590Y963570D01*
X-778840Y963070D01*
X-777090Y963570D01*
X-775690Y965070D01*
X-774990Y967320D01*
Y978070D01*
G01X-768140Y963070D02*
Y978070D01*
X-763765D01*
X-762365Y977320D01*
X-761490Y976320D01*
X-761140Y974320D01*
X-761490Y972320D01*
X-762540Y971070D01*
X-763765Y970320D01*
X-768140D01*
G01X-763765D02*
X-761140Y963070D01*
G01X-746940D02*
X-753940D01*
Y978070D01*
X-746940D01*
G01X-749740Y970820D02*
X-753940D01*
G01X-739740Y963070D02*
Y978070D01*
X-735365D01*
X-733965Y977320D01*
X-733090Y976320D01*
X-732740Y974320D01*
X-733090Y972320D01*
X-734140Y971070D01*
X-735365Y970320D01*
X-739740D01*
G01X-735365D02*
X-732740Y963070D01*
G01X-725715Y965070D02*
X-724315Y963820D01*
X-722740Y963070D01*
X-721340D01*
X-719940Y963820D01*
X-718890Y965070D01*
X-718365Y966820D01*
X-718715Y968570D01*
X-719590Y970070D01*
X-721165Y971070D01*
X-723265Y971570D01*
X-724490Y972570D01*
X-725015Y974320D01*
X-724665Y976070D01*
X-723790Y977320D01*
X-722565Y978070D01*
X-721340D01*
X-720115Y977570D01*
X-719065Y976320D01*
G01X-1545640Y998070D02*
Y1013070D01*
X-1547740Y1010070D01*
G01Y998070D02*
X-1543540D01*
G01X-1531440Y997570D02*
X-1531790Y997820D01*
Y998320D01*
X-1531440Y998570D01*
X-1531090Y998320D01*
Y997820D01*
X-1531440Y997570D01*
G01X-1507415Y998070D02*
X-1503040Y1013070D01*
X-1498665Y998070D01*
G01X-1500240Y1003320D02*
X-1505840D01*
G01X-1492515Y1000070D02*
X-1491115Y998820D01*
X-1489540Y998070D01*
X-1488140D01*
X-1486740Y998820D01*
X-1485690Y1000070D01*
X-1485165Y1001820D01*
X-1485515Y1003570D01*
X-1486390Y1005070D01*
X-1487965Y1006070D01*
X-1490065Y1006570D01*
X-1491290Y1007570D01*
X-1491815Y1009320D01*
X-1491465Y1011070D01*
X-1490590Y1012320D01*
X-1489365Y1013070D01*
X-1488140D01*
X-1486915Y1012570D01*
X-1485865Y1011320D01*
G01X-1478315Y1000070D02*
X-1476915Y998820D01*
X-1475340Y998070D01*
X-1473940D01*
X-1472540Y998820D01*
X-1471490Y1000070D01*
X-1470965Y1001820D01*
X-1471315Y1003570D01*
X-1472190Y1005070D01*
X-1473765Y1006070D01*
X-1475865Y1006570D01*
X-1477090Y1007570D01*
X-1477615Y1009320D01*
X-1477265Y1011070D01*
X-1476390Y1012320D01*
X-1475165Y1013070D01*
X-1473940D01*
X-1472715Y1012570D01*
X-1471665Y1011320D01*
G01X-1456940Y998070D02*
X-1463940D01*
Y1013070D01*
X-1456940D01*
G01X-1459740Y1005820D02*
X-1463940D01*
G01X-1450790Y998070D02*
Y1013070D01*
X-1446240Y1000570D01*
X-1441690Y1013070D01*
Y998070D01*
G01X-1430640Y1006070D02*
X-1429940Y1006820D01*
X-1429415Y1008070D01*
X-1429065Y1009820D01*
X-1429415Y1011320D01*
X-1430115Y1012320D01*
X-1431340Y1013070D01*
X-1436065D01*
Y998070D01*
X-1430290D01*
X-1429065Y999070D01*
X-1428365Y1000570D01*
X-1428015Y1002320D01*
X-1428365Y1004070D01*
X-1429415Y1005570D01*
X-1430640Y1006070D01*
X-1436065D01*
G01X-1421340Y1013070D02*
Y998070D01*
X-1414340D01*
G01X-1400140D02*
X-1407140D01*
Y1013070D01*
X-1400140D01*
G01X-1402940Y1005820D02*
X-1407140D01*
G01X-1373840Y1006070D02*
X-1373140Y1006820D01*
X-1372615Y1008070D01*
X-1372265Y1009820D01*
X-1372615Y1011320D01*
X-1373315Y1012320D01*
X-1374540Y1013070D01*
X-1379265D01*
Y998070D01*
X-1373490D01*
X-1372265Y999070D01*
X-1371565Y1000570D01*
X-1371215Y1002320D01*
X-1371565Y1004070D01*
X-1372615Y1005570D01*
X-1373840Y1006070D01*
X-1379265D01*
G01X-1361040Y998070D02*
X-1362440Y998320D01*
X-1363665Y999320D01*
X-1364715Y1000820D01*
X-1365415Y1002570D01*
X-1365765Y1004570D01*
Y1006570D01*
X-1365415Y1008570D01*
X-1364715Y1010320D01*
X-1363665Y1011820D01*
X-1362440Y1012820D01*
X-1361040Y1013070D01*
X-1359640Y1012820D01*
X-1358415Y1011820D01*
X-1357365Y1010320D01*
X-1356665Y1008570D01*
X-1356315Y1006570D01*
Y1004570D01*
X-1356665Y1002570D01*
X-1357365Y1000820D01*
X-1358415Y999320D01*
X-1359640Y998320D01*
X-1361040Y998070D01*
G01X-1351215D02*
X-1346840Y1013070D01*
X-1342465Y998070D01*
G01X-1344040Y1003320D02*
X-1349640D01*
G01X-1336140Y998070D02*
Y1013070D01*
X-1331765D01*
X-1330365Y1012320D01*
X-1329490Y1011320D01*
X-1329140Y1009320D01*
X-1329490Y1007320D01*
X-1330540Y1006070D01*
X-1331765Y1005320D01*
X-1336140D01*
G01X-1331765D02*
X-1329140Y998070D01*
G01X-1322290D02*
Y1013070D01*
X-1318790D01*
X-1317390Y1012320D01*
X-1316340Y1011320D01*
X-1315465Y1009820D01*
X-1314765Y1008070D01*
X-1314590Y1005570D01*
X-1314765Y1003070D01*
X-1315465Y1001320D01*
X-1316340Y999820D01*
X-1317390Y998820D01*
X-1318790Y998070D01*
X-1322290D01*
G01X-1293540D02*
Y1013070D01*
X-1289340D01*
X-1287940Y1012320D01*
X-1286890Y1010570D01*
X-1286540Y1008570D01*
X-1286890Y1006570D01*
X-1287765Y1005070D01*
X-1289340Y1004320D01*
X-1293540D01*
G01X-1272340Y998070D02*
X-1279340D01*
Y1013070D01*
X-1272340D01*
G01X-1275140Y1005820D02*
X-1279340D01*
G01X-1265140Y998070D02*
Y1013070D01*
X-1260765D01*
X-1259365Y1012320D01*
X-1258490Y1011320D01*
X-1258140Y1009320D01*
X-1258490Y1007320D01*
X-1259540Y1006070D01*
X-1260765Y1005320D01*
X-1265140D01*
G01X-1260765D02*
X-1258140Y998070D01*
G01X-1235340Y1013070D02*
X-1231140D01*
G01X-1233240D02*
Y998070D01*
G01X-1235340D02*
X-1231140D01*
G01X-1222540D02*
Y1013070D01*
X-1218340D01*
X-1216940Y1012320D01*
X-1215890Y1010570D01*
X-1215540Y1008570D01*
X-1215890Y1006570D01*
X-1216765Y1005070D01*
X-1218340Y1004320D01*
X-1222540D01*
G01X-1200990Y1011820D02*
X-1202040Y1012570D01*
X-1203265Y1013070D01*
X-1204665D01*
X-1206240Y1012320D01*
X-1207465Y1011070D01*
X-1208340Y1009570D01*
X-1209040Y1007070D01*
X-1209215Y1004820D01*
X-1208865Y1002570D01*
X-1208340Y1001070D01*
X-1207290Y999570D01*
X-1206065Y998570D01*
X-1204840Y998070D01*
X-1203615D01*
X-1202390Y998570D01*
X-1201340Y999320D01*
X-1200465Y1000320D01*
G01X-1192915Y1003070D02*
X-1188365D01*
G01X-1180815Y998070D02*
X-1176440Y1013070D01*
X-1172065Y998070D01*
G01X-1173640Y1003320D02*
X-1179240D01*
G01X-1164515Y1003070D02*
X-1159965D01*
G01X-1151365Y1004320D02*
X-1150140Y1006070D01*
X-1149090Y1007070D01*
X-1147690Y1007570D01*
X-1146465Y1007070D01*
X-1145590Y1006070D01*
X-1144890Y1004570D01*
X-1144715Y1002820D01*
X-1144890Y1001320D01*
X-1145590Y999820D01*
X-1146640Y998570D01*
X-1147865Y998070D01*
X-1149265Y998570D01*
X-1150490Y1000070D01*
X-1151190Y1002320D01*
X-1151365Y1004820D01*
X-1151015Y1008070D01*
X-1150490Y1009820D01*
X-1149615Y1011570D01*
X-1148390Y1012820D01*
X-1147165Y1013070D01*
X-1145940Y1012570D01*
X-1145065Y1011320D01*
G01X-1133840Y998070D02*
Y1013070D01*
X-1135940Y1010070D01*
G01Y998070D02*
X-1131740D01*
G01X-1119640Y1013070D02*
X-1121040Y1012570D01*
X-1122090Y1011320D01*
X-1122790Y1009820D01*
X-1123315Y1007820D01*
X-1123490Y1005570D01*
X-1123315Y1003320D01*
X-1122790Y1001320D01*
X-1122090Y999820D01*
X-1121040Y998570D01*
X-1119640Y998070D01*
X-1118240Y998570D01*
X-1117190Y999820D01*
X-1116490Y1001320D01*
X-1115965Y1003320D01*
X-1115790Y1005570D01*
X-1115965Y1007820D01*
X-1116490Y1009820D01*
X-1117190Y1011320D01*
X-1118240Y1012570D01*
X-1119640Y1013070D01*
G01X-1106315Y993070D02*
X-1108065Y995570D01*
X-1108940Y998070D01*
Y1008070D01*
X-1108065Y1010570D01*
X-1106315Y1013070D01*
G01X-1094740D02*
Y998070D01*
X-1087740D01*
G01X-1081415D02*
X-1077040Y1013070D01*
X-1072665Y998070D01*
G01X-1074240Y1003320D02*
X-1079840D01*
G01X-1062840Y1013070D02*
Y998070D01*
G01X-1066865Y1013070D02*
X-1058815D01*
G01X-1045140Y998070D02*
X-1052140D01*
Y1013070D01*
X-1045140D01*
G01X-1047940Y1005820D02*
X-1052140D01*
G01X-1038115Y1000070D02*
X-1036715Y998820D01*
X-1035140Y998070D01*
X-1033740D01*
X-1032340Y998820D01*
X-1031290Y1000070D01*
X-1030765Y1001820D01*
X-1031115Y1003570D01*
X-1031990Y1005070D01*
X-1033565Y1006070D01*
X-1035665Y1006570D01*
X-1036890Y1007570D01*
X-1037415Y1009320D01*
X-1037065Y1011070D01*
X-1036190Y1012320D01*
X-1034965Y1013070D01*
X-1033740D01*
X-1032515Y1012570D01*
X-1031465Y1011320D01*
G01X-1020240Y1013070D02*
Y998070D01*
G01X-1024265Y1013070D02*
X-1016215D01*
G01X-995340Y998070D02*
Y1013070D01*
X-990965D01*
X-989565Y1012320D01*
X-988690Y1011320D01*
X-988340Y1009320D01*
X-988690Y1007320D01*
X-989740Y1006070D01*
X-990965Y1005320D01*
X-995340D01*
G01X-990965D02*
X-988340Y998070D01*
G01X-974140D02*
X-981140D01*
Y1013070D01*
X-974140D01*
G01X-976940Y1005820D02*
X-981140D01*
G01X-967815Y1013070D02*
X-963440Y998070D01*
X-959065Y1013070D01*
G01X-951340D02*
X-947140D01*
G01X-949240D02*
Y998070D01*
G01X-951340D02*
X-947140D01*
G01X-938715Y1000070D02*
X-937315Y998820D01*
X-935740Y998070D01*
X-934340D01*
X-932940Y998820D01*
X-931890Y1000070D01*
X-931365Y1001820D01*
X-931715Y1003570D01*
X-932590Y1005070D01*
X-934165Y1006070D01*
X-936265Y1006570D01*
X-937490Y1007570D01*
X-938015Y1009320D01*
X-937665Y1011070D01*
X-936790Y1012320D01*
X-935565Y1013070D01*
X-934340D01*
X-933115Y1012570D01*
X-932065Y1011320D01*
G01X-922940Y1013070D02*
X-918740D01*
G01X-920840D02*
Y998070D01*
G01X-922940D02*
X-918740D01*
G01X-906640D02*
X-908040Y998320D01*
X-909265Y999320D01*
X-910315Y1000820D01*
X-911015Y1002570D01*
X-911365Y1004570D01*
Y1006570D01*
X-911015Y1008570D01*
X-910315Y1010320D01*
X-909265Y1011820D01*
X-908040Y1012820D01*
X-906640Y1013070D01*
X-905240Y1012820D01*
X-904015Y1011820D01*
X-902965Y1010320D01*
X-902265Y1008570D01*
X-901915Y1006570D01*
Y1004570D01*
X-902265Y1002570D01*
X-902965Y1000820D01*
X-904015Y999320D01*
X-905240Y998320D01*
X-906640Y998070D01*
G01X-896465D02*
Y1013070D01*
X-888415Y998070D01*
Y1013070D01*
G01X-877365Y993070D02*
X-875615Y995570D01*
X-874740Y998070D01*
Y1008070D01*
X-875615Y1010570D01*
X-877365Y1013070D01*
G01X-853515Y1000070D02*
X-852115Y998820D01*
X-850540Y998070D01*
X-849140D01*
X-847740Y998820D01*
X-846690Y1000070D01*
X-846165Y1001820D01*
X-846515Y1003570D01*
X-847390Y1005070D01*
X-848965Y1006070D01*
X-851065Y1006570D01*
X-852290Y1007570D01*
X-852815Y1009320D01*
X-852465Y1011070D01*
X-851590Y1012320D01*
X-850365Y1013070D01*
X-849140D01*
X-847915Y1012570D01*
X-846865Y1011320D01*
G01X-835640Y1013070D02*
Y998070D01*
G01X-839665Y1013070D02*
X-831615D01*
G01X-825815Y998070D02*
X-821440Y1013070D01*
X-817065Y998070D01*
G01X-818640Y1003320D02*
X-824240D01*
G01X-811265Y998070D02*
Y1013070D01*
X-803215Y998070D01*
Y1013070D01*
G01X-796890Y998070D02*
Y1013070D01*
X-793390D01*
X-791990Y1012320D01*
X-790940Y1011320D01*
X-790065Y1009820D01*
X-789365Y1008070D01*
X-789190Y1005570D01*
X-789365Y1003070D01*
X-790065Y1001320D01*
X-790940Y999820D01*
X-791990Y998820D01*
X-793390Y998070D01*
X-796890D01*
G01X-783215D02*
X-778840Y1013070D01*
X-774465Y998070D01*
G01X-776040Y1003320D02*
X-781640D01*
G01X-768140Y998070D02*
Y1013070D01*
X-763765D01*
X-762365Y1012320D01*
X-761490Y1011320D01*
X-761140Y1009320D01*
X-761490Y1007320D01*
X-762540Y1006070D01*
X-763765Y1005320D01*
X-768140D01*
G01X-763765D02*
X-761140Y998070D01*
G01X-754290D02*
Y1013070D01*
X-750790D01*
X-749390Y1012320D01*
X-748340Y1011320D01*
X-747465Y1009820D01*
X-746765Y1008070D01*
X-746590Y1005570D01*
X-746765Y1003070D01*
X-747465Y1001320D01*
X-748340Y999820D01*
X-749390Y998820D01*
X-750790Y998070D01*
X-754290D01*
G01X-736240Y997570D02*
X-736590Y997820D01*
Y998320D01*
X-736240Y998570D01*
X-735890Y998320D01*
Y997820D01*
X-736240Y997570D01*
G01X-1549665Y1033070D02*
Y1048070D01*
X-1541615Y1033070D01*
Y1048070D01*
G01X-1531440Y1033070D02*
X-1532840Y1033320D01*
X-1534065Y1034320D01*
X-1535115Y1035820D01*
X-1535815Y1037570D01*
X-1536165Y1039570D01*
Y1041570D01*
X-1535815Y1043570D01*
X-1535115Y1045320D01*
X-1534065Y1046820D01*
X-1532840Y1047820D01*
X-1531440Y1048070D01*
X-1530040Y1047820D01*
X-1528815Y1046820D01*
X-1527765Y1045320D01*
X-1527065Y1043570D01*
X-1526715Y1041570D01*
Y1039570D01*
X-1527065Y1037570D01*
X-1527765Y1035820D01*
X-1528815Y1034320D01*
X-1530040Y1033320D01*
X-1531440Y1033070D01*
G01X-1517240Y1048070D02*
Y1033070D01*
G01X-1521265Y1048070D02*
X-1513215D01*
G01X-1499540Y1033070D02*
X-1506540D01*
Y1048070D01*
X-1499540D01*
G01X-1502340Y1040820D02*
X-1506540D01*
G01X-1492515Y1035070D02*
X-1491115Y1033820D01*
X-1489540Y1033070D01*
X-1488140D01*
X-1486740Y1033820D01*
X-1485690Y1035070D01*
X-1485165Y1036820D01*
X-1485515Y1038570D01*
X-1486390Y1040070D01*
X-1487965Y1041070D01*
X-1490065Y1041570D01*
X-1491290Y1042570D01*
X-1491815Y1044320D01*
X-1491465Y1046070D01*
X-1490590Y1047320D01*
X-1489365Y1048070D01*
X-1488140D01*
X-1486915Y1047570D01*
X-1485865Y1046320D01*
G01X-1474640Y1032570D02*
X-1474990Y1032820D01*
Y1033320D01*
X-1474640Y1033570D01*
X-1474290Y1033320D01*
Y1032820D01*
X-1474640Y1032570D01*
G01Y1039320D02*
X-1474990Y1039570D01*
Y1040070D01*
X-1474640Y1040320D01*
X-1474290Y1040070D01*
Y1039570D01*
X-1474640Y1039320D01*
G01X-1450090Y1048070D02*
Y1037320D01*
X-1449390Y1035070D01*
X-1447990Y1033570D01*
X-1446240Y1033070D01*
X-1444490Y1033570D01*
X-1443090Y1035070D01*
X-1442390Y1037320D01*
Y1048070D01*
G01X-1436065Y1033070D02*
Y1048070D01*
X-1428015Y1033070D01*
Y1048070D01*
G01X-1421340D02*
Y1033070D01*
X-1414340D01*
G01X-1400140D02*
X-1407140D01*
Y1048070D01*
X-1400140D01*
G01X-1402940Y1040820D02*
X-1407140D01*
G01X-1393115Y1035070D02*
X-1391715Y1033820D01*
X-1390140Y1033070D01*
X-1388740D01*
X-1387340Y1033820D01*
X-1386290Y1035070D01*
X-1385765Y1036820D01*
X-1386115Y1038570D01*
X-1386990Y1040070D01*
X-1388565Y1041070D01*
X-1390665Y1041570D01*
X-1391890Y1042570D01*
X-1392415Y1044320D01*
X-1392065Y1046070D01*
X-1391190Y1047320D01*
X-1389965Y1048070D01*
X-1388740D01*
X-1387515Y1047570D01*
X-1386465Y1046320D01*
G01X-1378915Y1035070D02*
X-1377515Y1033820D01*
X-1375940Y1033070D01*
X-1374540D01*
X-1373140Y1033820D01*
X-1372090Y1035070D01*
X-1371565Y1036820D01*
X-1371915Y1038570D01*
X-1372790Y1040070D01*
X-1374365Y1041070D01*
X-1376465Y1041570D01*
X-1377690Y1042570D01*
X-1378215Y1044320D01*
X-1377865Y1046070D01*
X-1376990Y1047320D01*
X-1375765Y1048070D01*
X-1374540D01*
X-1373315Y1047570D01*
X-1372265Y1046320D01*
G01X-1346840Y1033070D02*
X-1348240Y1033320D01*
X-1349465Y1034320D01*
X-1350515Y1035820D01*
X-1351215Y1037570D01*
X-1351565Y1039570D01*
Y1041570D01*
X-1351215Y1043570D01*
X-1350515Y1045320D01*
X-1349465Y1046820D01*
X-1348240Y1047820D01*
X-1346840Y1048070D01*
X-1345440Y1047820D01*
X-1344215Y1046820D01*
X-1343165Y1045320D01*
X-1342465Y1043570D01*
X-1342115Y1041570D01*
Y1039570D01*
X-1342465Y1037570D01*
X-1343165Y1035820D01*
X-1344215Y1034320D01*
X-1345440Y1033320D01*
X-1346840Y1033070D01*
G01X-1332640Y1048070D02*
Y1033070D01*
G01X-1336665Y1048070D02*
X-1328615D01*
G01X-1322115Y1033070D02*
Y1048070D01*
G01X-1314765D02*
Y1033070D01*
G01Y1040570D02*
X-1322115D01*
G01X-1300740Y1033070D02*
X-1307740D01*
Y1048070D01*
X-1300740D01*
G01X-1303540Y1040820D02*
X-1307740D01*
G01X-1293540Y1033070D02*
Y1048070D01*
X-1289165D01*
X-1287765Y1047320D01*
X-1286890Y1046320D01*
X-1286540Y1044320D01*
X-1286890Y1042320D01*
X-1287940Y1041070D01*
X-1289165Y1040320D01*
X-1293540D01*
G01X-1289165D02*
X-1286540Y1033070D01*
G01X-1281090Y1048070D02*
X-1278640Y1033070D01*
X-1275840Y1048070D01*
X-1273040Y1033070D01*
X-1270590Y1048070D01*
G01X-1263740D02*
X-1259540D01*
G01X-1261640D02*
Y1033070D01*
G01X-1263740D02*
X-1259540D01*
G01X-1251115Y1035070D02*
X-1249715Y1033820D01*
X-1248140Y1033070D01*
X-1246740D01*
X-1245340Y1033820D01*
X-1244290Y1035070D01*
X-1243765Y1036820D01*
X-1244115Y1038570D01*
X-1244990Y1040070D01*
X-1246565Y1041070D01*
X-1248665Y1041570D01*
X-1249890Y1042570D01*
X-1250415Y1044320D01*
X-1250065Y1046070D01*
X-1249190Y1047320D01*
X-1247965Y1048070D01*
X-1246740D01*
X-1245515Y1047570D01*
X-1244465Y1046320D01*
G01X-1229740Y1033070D02*
X-1236740D01*
Y1048070D01*
X-1229740D01*
G01X-1232540Y1040820D02*
X-1236740D01*
G01X-1208515Y1035070D02*
X-1207115Y1033820D01*
X-1205540Y1033070D01*
X-1204140D01*
X-1202740Y1033820D01*
X-1201690Y1035070D01*
X-1201165Y1036820D01*
X-1201515Y1038570D01*
X-1202390Y1040070D01*
X-1203965Y1041070D01*
X-1206065Y1041570D01*
X-1207290Y1042570D01*
X-1207815Y1044320D01*
X-1207465Y1046070D01*
X-1206590Y1047320D01*
X-1205365Y1048070D01*
X-1204140D01*
X-1202915Y1047570D01*
X-1201865Y1046320D01*
G01X-1194140Y1033070D02*
Y1048070D01*
X-1189940D01*
X-1188540Y1047320D01*
X-1187490Y1045570D01*
X-1187140Y1043570D01*
X-1187490Y1041570D01*
X-1188365Y1040070D01*
X-1189940Y1039320D01*
X-1194140D01*
G01X-1172940Y1033070D02*
X-1179940D01*
Y1048070D01*
X-1172940D01*
G01X-1175740Y1040820D02*
X-1179940D01*
G01X-1158390Y1046820D02*
X-1159440Y1047570D01*
X-1160665Y1048070D01*
X-1162065D01*
X-1163640Y1047320D01*
X-1164865Y1046070D01*
X-1165740Y1044570D01*
X-1166440Y1042070D01*
X-1166615Y1039820D01*
X-1166265Y1037570D01*
X-1165740Y1036070D01*
X-1164690Y1034570D01*
X-1163465Y1033570D01*
X-1162240Y1033070D01*
X-1161015D01*
X-1159790Y1033570D01*
X-1158740Y1034320D01*
X-1157865Y1035320D01*
G01X-1150140Y1048070D02*
X-1145940D01*
G01X-1148040D02*
Y1033070D01*
G01X-1150140D02*
X-1145940D01*
G01X-1137165D02*
Y1048070D01*
X-1130515D01*
G01X-1132965Y1040820D02*
X-1137165D01*
G01X-1121740Y1048070D02*
X-1117540D01*
G01X-1119640D02*
Y1033070D01*
G01X-1121740D02*
X-1117540D01*
G01X-1101940D02*
X-1108940D01*
Y1048070D01*
X-1101940D01*
G01X-1104740Y1040820D02*
X-1108940D01*
G01X-1095090Y1033070D02*
Y1048070D01*
X-1091590D01*
X-1090190Y1047320D01*
X-1089140Y1046320D01*
X-1088265Y1044820D01*
X-1087565Y1043070D01*
X-1087390Y1040570D01*
X-1087565Y1038070D01*
X-1088265Y1036320D01*
X-1089140Y1034820D01*
X-1090190Y1033820D01*
X-1091590Y1033070D01*
X-1095090D01*
G01X-1077040Y1032570D02*
X-1077390Y1032820D01*
Y1033320D01*
X-1077040Y1033570D01*
X-1076690Y1033320D01*
Y1032820D01*
X-1077040Y1032570D01*
G01Y1039320D02*
X-1077390Y1039570D01*
Y1040070D01*
X-1077040Y1040320D01*
X-1076690Y1040070D01*
Y1039570D01*
X-1077040Y1039320D01*
G01X-1475000Y-800000D02*
Y-850000D01*
G01Y1350000D02*
Y1300000D01*
G01X-1050000Y-800000D02*
Y-850000D01*
G01Y1350000D02*
Y1300000D01*
G01X-625000Y-800000D02*
Y-850000D01*
G01Y1350000D02*
Y1300000D01*
G01X-200000Y-800000D02*
Y-850000D01*
G01Y1350000D02*
Y1300000D01*
G01X225000Y-800000D02*
Y-850000D01*
G01Y1350000D02*
Y1300000D01*
G01X890000Y-735000D02*
X640000D01*
G01X890000Y-705000D02*
X640000D01*
G01X890000Y-675000D02*
X640000D01*
G01X890000Y-640000D02*
X640000D01*
G01X890000Y-610000D02*
X640000D01*
G01X890000Y-580000D02*
X640000D01*
G01X650000Y-800000D02*
Y-850000D01*
G01Y1350000D02*
Y1300000D01*
G01X808000Y-550000D02*
Y-800000D01*
G01X905110Y-544870D02*
Y-529870D01*
X909660Y-542370D01*
X914210Y-529870D01*
Y-544870D01*
G01X920185Y-542870D02*
X921585Y-544120D01*
X923160Y-544870D01*
X924560D01*
X925960Y-544120D01*
X927010Y-542870D01*
X927535Y-541120D01*
X927185Y-539370D01*
X926310Y-537870D01*
X924735Y-536870D01*
X922635Y-536370D01*
X921410Y-535370D01*
X920885Y-533620D01*
X921235Y-531870D01*
X922110Y-530620D01*
X923335Y-529870D01*
X924560D01*
X925785Y-530370D01*
X926835Y-531620D01*
G01X948760Y-544870D02*
Y-529870D01*
X952960D01*
X954360Y-530620D01*
X955410Y-532370D01*
X955760Y-534370D01*
X955410Y-536370D01*
X954535Y-537870D01*
X952960Y-538620D01*
X948760D01*
G01X962610Y-544870D02*
Y-529870D01*
X966110D01*
X967510Y-530620D01*
X968560Y-531620D01*
X969435Y-533120D01*
X970135Y-534870D01*
X970310Y-537370D01*
X970135Y-539870D01*
X969435Y-541620D01*
X968560Y-543120D01*
X967510Y-544120D01*
X966110Y-544870D01*
X962610D01*
G01X976110D02*
Y-529870D01*
X980660Y-542370D01*
X985210Y-529870D01*
Y-544870D01*
G01X1004685Y-529870D02*
X1009060Y-544870D01*
X1013435Y-529870D01*
G01X1026760Y-544870D02*
X1019760D01*
Y-529870D01*
X1026760D01*
G01X1023960Y-537120D02*
X1019760D01*
G01X1033960Y-544870D02*
Y-529870D01*
X1038335D01*
X1039735Y-530620D01*
X1040610Y-531620D01*
X1040960Y-533620D01*
X1040610Y-535620D01*
X1039560Y-536870D01*
X1038335Y-537620D01*
X1033960D01*
G01X1038335D02*
X1040960Y-544870D01*
G01X1051660Y-545370D02*
X1051310Y-545120D01*
Y-544620D01*
X1051660Y-544370D01*
X1052010Y-544620D01*
Y-545120D01*
X1051660Y-545370D01*
G01Y-538620D02*
X1051310Y-538370D01*
Y-537870D01*
X1051660Y-537620D01*
X1052010Y-537870D01*
Y-538370D01*
X1051660Y-538620D01*
G01X1076210Y-544870D02*
Y-529870D01*
X1079710D01*
X1081110Y-530620D01*
X1082160Y-531620D01*
X1083035Y-533120D01*
X1083735Y-534870D01*
X1083910Y-537370D01*
X1083735Y-539870D01*
X1083035Y-541620D01*
X1082160Y-543120D01*
X1081110Y-544120D01*
X1079710Y-544870D01*
X1076210D01*
G01X1094260Y-545370D02*
X1093910Y-545120D01*
Y-544620D01*
X1094260Y-544370D01*
X1094610Y-544620D01*
Y-545120D01*
X1094260Y-545370D01*
G01X1108460Y-544870D02*
Y-529870D01*
X1106360Y-532870D01*
G01Y-544870D02*
X1110560D01*
G01X905680Y-523980D02*
Y-508980D01*
X910230Y-521480D01*
X914780Y-508980D01*
Y-523980D01*
G01X920755Y-521980D02*
X922155Y-523230D01*
X923730Y-523980D01*
X925130D01*
X926530Y-523230D01*
X927580Y-521980D01*
X928105Y-520230D01*
X927755Y-518480D01*
X926880Y-516980D01*
X925305Y-515980D01*
X923205Y-515480D01*
X921980Y-514480D01*
X921455Y-512730D01*
X921805Y-510980D01*
X922680Y-509730D01*
X923905Y-508980D01*
X925130D01*
X926355Y-509480D01*
X927405Y-510730D01*
G01X949330Y-523980D02*
Y-508980D01*
X953530D01*
X954930Y-509730D01*
X955980Y-511480D01*
X956330Y-513480D01*
X955980Y-515480D01*
X955105Y-516980D01*
X953530Y-517730D01*
X949330D01*
G01X962655Y-523980D02*
X967030Y-508980D01*
X971405Y-523980D01*
G01X969830Y-518730D02*
X964230D01*
G01X977730Y-523980D02*
Y-508980D01*
X982105D01*
X983505Y-509730D01*
X984380Y-510730D01*
X984730Y-512730D01*
X984380Y-514730D01*
X983330Y-515980D01*
X982105Y-516730D01*
X977730D01*
G01X982105D02*
X984730Y-523980D01*
G01X995430Y-508980D02*
Y-523980D01*
G01X991405Y-508980D02*
X999455D01*
G01X1019805Y-523980D02*
Y-508980D01*
X1027855Y-523980D01*
Y-508980D01*
G01X1038030Y-523980D02*
X1036630Y-523730D01*
X1035405Y-522730D01*
X1034355Y-521230D01*
X1033655Y-519480D01*
X1033305Y-517480D01*
Y-515480D01*
X1033655Y-513480D01*
X1034355Y-511730D01*
X1035405Y-510230D01*
X1036630Y-509230D01*
X1038030Y-508980D01*
X1039430Y-509230D01*
X1040655Y-510230D01*
X1041705Y-511730D01*
X1042405Y-513480D01*
X1042755Y-515480D01*
Y-517480D01*
X1042405Y-519480D01*
X1041705Y-521230D01*
X1040655Y-522730D01*
X1039430Y-523730D01*
X1038030Y-523980D01*
G01X1052230Y-524480D02*
X1051880Y-524230D01*
Y-523730D01*
X1052230Y-523480D01*
X1052580Y-523730D01*
Y-524230D01*
X1052230Y-524480D01*
G01Y-517730D02*
X1051880Y-517480D01*
Y-516980D01*
X1052230Y-516730D01*
X1052580Y-516980D01*
Y-517480D01*
X1052230Y-517730D01*
G01X1076955Y-523980D02*
X1084305Y-508980D01*
G01X1076955D02*
X1084305Y-523980D01*
G01X1094830D02*
X1096055Y-523730D01*
X1097455Y-522980D01*
X1098330Y-521730D01*
X1098680Y-519980D01*
X1098330Y-518230D01*
X1097280Y-516730D01*
X1095705Y-515980D01*
X1093955D01*
X1092905Y-515480D01*
X1092030Y-514230D01*
X1091680Y-512480D01*
X1092205Y-510730D01*
X1093430Y-509480D01*
X1094830Y-508980D01*
X1096230Y-509480D01*
X1097455Y-510730D01*
X1097980Y-512480D01*
X1097630Y-514230D01*
X1096755Y-515480D01*
X1095705Y-515980D01*
X1093955D01*
X1092380Y-516730D01*
X1091330Y-518230D01*
X1090980Y-519980D01*
X1091330Y-521730D01*
X1092205Y-522980D01*
X1093605Y-523730D01*
X1094830Y-523980D01*
G01X1109030D02*
X1110255Y-523730D01*
X1111655Y-522980D01*
X1112530Y-521730D01*
X1112880Y-519980D01*
X1112530Y-518230D01*
X1111480Y-516730D01*
X1109905Y-515980D01*
X1108155D01*
X1107105Y-515480D01*
X1106230Y-514230D01*
X1105880Y-512480D01*
X1106405Y-510730D01*
X1107630Y-509480D01*
X1109030Y-508980D01*
X1110430Y-509480D01*
X1111655Y-510730D01*
X1112180Y-512480D01*
X1111830Y-514230D01*
X1110955Y-515480D01*
X1109905Y-515980D01*
X1108155D01*
X1106580Y-516730D01*
X1105530Y-518230D01*
X1105180Y-519980D01*
X1105530Y-521730D01*
X1106405Y-522980D01*
X1107805Y-523730D01*
X1109030Y-523980D01*
G01X1122880D02*
X1123230Y-520730D01*
X1123755Y-517980D01*
X1124455Y-515480D01*
X1125330Y-512730D01*
X1126730Y-508980D01*
X1119730D01*
G01X1133580Y-521730D02*
X1134630Y-522980D01*
X1135855Y-523730D01*
X1137430Y-523980D01*
X1139005Y-523480D01*
X1140230Y-522480D01*
X1141105Y-520730D01*
X1141280Y-518730D01*
X1140930Y-516730D01*
X1140055Y-515480D01*
X1138830Y-514480D01*
X1137605Y-514230D01*
X1136380Y-514480D01*
X1134805Y-515480D01*
X1135330Y-508980D01*
X1140055D01*
G01X1151280Y-523980D02*
X1151630Y-520730D01*
X1152155Y-517980D01*
X1152855Y-515480D01*
X1153730Y-512730D01*
X1155130Y-508980D01*
X1148130D01*
G01X1161980Y-520980D02*
X1163030Y-522730D01*
X1164430Y-523730D01*
X1166005Y-523980D01*
X1167405Y-523730D01*
X1168805Y-522480D01*
X1169680Y-520980D01*
X1169855Y-519480D01*
X1169505Y-517730D01*
X1168280Y-516480D01*
X1167055Y-515980D01*
X1165480D01*
G01X1167055D02*
X1168105Y-515230D01*
X1168980Y-513980D01*
X1169330Y-512480D01*
X1168980Y-510980D01*
X1168105Y-509730D01*
X1166530Y-508980D01*
X1164955Y-509230D01*
X1163380Y-510230D01*
G01X1177755Y-518980D02*
X1182305D01*
G01X1194230Y-508980D02*
X1192830Y-509480D01*
X1191780Y-510730D01*
X1191080Y-512230D01*
X1190555Y-514230D01*
X1190380Y-516480D01*
X1190555Y-518730D01*
X1191080Y-520730D01*
X1191780Y-522230D01*
X1192830Y-523480D01*
X1194230Y-523980D01*
X1195630Y-523480D01*
X1196680Y-522230D01*
X1197380Y-520730D01*
X1197905Y-518730D01*
X1198080Y-516480D01*
X1197905Y-514230D01*
X1197380Y-512230D01*
X1196680Y-510730D01*
X1195630Y-509480D01*
X1194230Y-508980D01*
G01X1208430D02*
X1207030Y-509480D01*
X1205980Y-510730D01*
X1205280Y-512230D01*
X1204755Y-514230D01*
X1204580Y-516480D01*
X1204755Y-518730D01*
X1205280Y-520730D01*
X1205980Y-522230D01*
X1207030Y-523480D01*
X1208430Y-523980D01*
X1209830Y-523480D01*
X1210880Y-522230D01*
X1211580Y-520730D01*
X1212105Y-518730D01*
X1212280Y-516480D01*
X1212105Y-514230D01*
X1211580Y-512230D01*
X1210880Y-510730D01*
X1209830Y-509480D01*
X1208430Y-508980D01*
G01X1222630Y-523980D02*
Y-508980D01*
X1220530Y-511980D01*
G01Y-523980D02*
X1224730D01*
G01X940000Y-770000D02*
Y-720000D01*
G01X976100Y-655000D02*
Y-640000D01*
X980300D01*
X981700Y-640750D01*
X982750Y-642500D01*
X983100Y-644500D01*
X982750Y-646500D01*
X981875Y-648000D01*
X980300Y-648750D01*
X976100D01*
G01X997650Y-641250D02*
X996600Y-640500D01*
X995375Y-640000D01*
X993975D01*
X992400Y-640750D01*
X991175Y-642000D01*
X990300Y-643500D01*
X989600Y-646000D01*
X989425Y-648250D01*
X989775Y-650500D01*
X990300Y-652000D01*
X991350Y-653500D01*
X992575Y-654500D01*
X993800Y-655000D01*
X995025D01*
X996250Y-654500D01*
X997300Y-653750D01*
X998175Y-652750D01*
G01X1009400Y-647000D02*
X1010100Y-646250D01*
X1010625Y-645000D01*
X1010975Y-643250D01*
X1010625Y-641750D01*
X1009925Y-640750D01*
X1008700Y-640000D01*
X1003975D01*
Y-655000D01*
X1009750D01*
X1010975Y-654000D01*
X1011675Y-652500D01*
X1012025Y-650750D01*
X1011675Y-649000D01*
X1010625Y-647500D01*
X1009400Y-647000D01*
X1003975D01*
G01X1032025Y-655000D02*
X1036400Y-640000D01*
X1040775Y-655000D01*
G01X1039200Y-649750D02*
X1033600D01*
G01X1046925Y-653000D02*
X1048325Y-654250D01*
X1049900Y-655000D01*
X1051300D01*
X1052700Y-654250D01*
X1053750Y-653000D01*
X1054275Y-651250D01*
X1053925Y-649500D01*
X1053050Y-648000D01*
X1051475Y-647000D01*
X1049375Y-646500D01*
X1048150Y-645500D01*
X1047625Y-643750D01*
X1047975Y-642000D01*
X1048850Y-640750D01*
X1050075Y-640000D01*
X1051300D01*
X1052525Y-640500D01*
X1053575Y-641750D01*
G01X1061125Y-653000D02*
X1062525Y-654250D01*
X1064100Y-655000D01*
X1065500D01*
X1066900Y-654250D01*
X1067950Y-653000D01*
X1068475Y-651250D01*
X1068125Y-649500D01*
X1067250Y-648000D01*
X1065675Y-647000D01*
X1063575Y-646500D01*
X1062350Y-645500D01*
X1061825Y-643750D01*
X1062175Y-642000D01*
X1063050Y-640750D01*
X1064275Y-640000D01*
X1065500D01*
X1066725Y-640500D01*
X1067775Y-641750D01*
G01X1082500Y-655000D02*
X1075500D01*
Y-640000D01*
X1082500D01*
G01X1079700Y-647250D02*
X1075500D01*
G01X1088650Y-655000D02*
Y-640000D01*
X1093200Y-652500D01*
X1097750Y-640000D01*
Y-655000D01*
G01X1108800Y-647000D02*
X1109500Y-646250D01*
X1110025Y-645000D01*
X1110375Y-643250D01*
X1110025Y-641750D01*
X1109325Y-640750D01*
X1108100Y-640000D01*
X1103375D01*
Y-655000D01*
X1109150D01*
X1110375Y-654000D01*
X1111075Y-652500D01*
X1111425Y-650750D01*
X1111075Y-649000D01*
X1110025Y-647500D01*
X1108800Y-647000D01*
X1103375D01*
G01X1118100Y-640000D02*
Y-655000D01*
X1125100D01*
G01X1135800D02*
Y-648250D01*
X1132300Y-640000D01*
G01X1139300D02*
X1135800Y-648250D01*
G01X1160350Y-655000D02*
Y-640000D01*
X1163850D01*
X1165250Y-640750D01*
X1166300Y-641750D01*
X1167175Y-643250D01*
X1167875Y-645000D01*
X1168050Y-647500D01*
X1167875Y-650000D01*
X1167175Y-651750D01*
X1166300Y-653250D01*
X1165250Y-654250D01*
X1163850Y-655000D01*
X1160350D01*
G01X1174900D02*
Y-640000D01*
X1179275D01*
X1180675Y-640750D01*
X1181550Y-641750D01*
X1181900Y-643750D01*
X1181550Y-645750D01*
X1180500Y-647000D01*
X1179275Y-647750D01*
X1174900D01*
G01X1179275D02*
X1181900Y-655000D01*
G01X1188225D02*
X1192600Y-640000D01*
X1196975Y-655000D01*
G01X1195400Y-649750D02*
X1189800D01*
G01X1201550Y-640000D02*
X1204000Y-655000D01*
X1206800Y-640000D01*
X1209600Y-655000D01*
X1212050Y-640000D01*
G01X1218900D02*
X1223100D01*
G01X1221000D02*
Y-655000D01*
G01X1218900D02*
X1223100D01*
G01X1231175D02*
Y-640000D01*
X1239225Y-655000D01*
Y-640000D01*
G01X1250450Y-647500D02*
X1253950D01*
Y-652000D01*
X1252900Y-653500D01*
X1251675Y-654500D01*
X1249925Y-655000D01*
X1248175Y-654500D01*
X1246950Y-653500D01*
X1245900Y-652000D01*
X1245200Y-650250D01*
X1244850Y-648250D01*
Y-646500D01*
X1245200Y-645000D01*
X1245900Y-643250D01*
X1246950Y-641750D01*
X1248000Y-640750D01*
X1249400Y-640000D01*
X1250625D01*
X1252025Y-640500D01*
X1253075Y-641500D01*
G01X1263250Y-657750D02*
X1263950Y-654500D01*
G01X1292000Y-640000D02*
Y-655000D01*
G01X1287975Y-640000D02*
X1296025D01*
G01X1306200Y-655000D02*
X1304800Y-654750D01*
X1303575Y-653750D01*
X1302525Y-652250D01*
X1301825Y-650500D01*
X1301475Y-648500D01*
Y-646500D01*
X1301825Y-644500D01*
X1302525Y-642750D01*
X1303575Y-641250D01*
X1304800Y-640250D01*
X1306200Y-640000D01*
X1307600Y-640250D01*
X1308825Y-641250D01*
X1309875Y-642750D01*
X1310575Y-644500D01*
X1310925Y-646500D01*
Y-648500D01*
X1310575Y-650500D01*
X1309875Y-652250D01*
X1308825Y-653750D01*
X1307600Y-654750D01*
X1306200Y-655000D01*
G01X1316900D02*
Y-640000D01*
X1321100D01*
X1322500Y-640750D01*
X1323550Y-642500D01*
X1323900Y-644500D01*
X1323550Y-646500D01*
X1322675Y-648000D01*
X1321100Y-648750D01*
X1316900D01*
G01X990000Y-770000D02*
Y-720000D01*
G01X1075000Y-800000D02*
Y-850000D01*
G01Y1350000D02*
Y1300000D01*
G01X1105000Y-770000D02*
Y-720000D01*
G01X1230000Y-800000D02*
Y-770000D01*
G01X1305250Y-790000D02*
Y-775000D01*
X1303150Y-778000D01*
G01Y-790000D02*
X1307350D01*
G01X1350000Y-770000D02*
Y-720000D01*
G01X1370250Y-790000D02*
Y-775000D01*
X1368150Y-778000D01*
G01Y-790000D02*
X1372350D01*
G01X1450000Y-300000D02*
X1400000D01*
G01Y250000D02*
X1450000D01*
G01Y800000D02*
X1400000D01*
G54D17*
G01X-475083Y-293000D02*
Y-268000D01*
X-468083D01*
X-465750Y-269250D01*
X-464000Y-272167D01*
X-463417Y-275500D01*
X-464000Y-278833D01*
X-465458Y-281334D01*
X-468083Y-282584D01*
X-475083D01*
G01X-451383Y-293000D02*
Y-268000D01*
X-444092D01*
X-441758Y-269250D01*
X-440300Y-270917D01*
X-439717Y-274250D01*
X-440300Y-277584D01*
X-442050Y-279666D01*
X-444092Y-280917D01*
X-451383D01*
G01X-444092D02*
X-439717Y-293000D01*
G01X-425350Y-268000D02*
X-418350D01*
G01X-421850D02*
Y-293000D01*
G01X-425350D02*
X-418350D01*
G01X-405734D02*
Y-268000D01*
X-398150Y-288833D01*
X-390566Y-268000D01*
Y-293000D01*
G01X-381742D02*
X-374450Y-268000D01*
X-367158Y-293000D01*
G01X-369784Y-284250D02*
X-379117D01*
G01X-356583Y-293000D02*
Y-268000D01*
X-349292D01*
X-346958Y-269250D01*
X-345500Y-270917D01*
X-344917Y-274250D01*
X-345500Y-277584D01*
X-347250Y-279666D01*
X-349292Y-280917D01*
X-356583D01*
G01X-349292D02*
X-344917Y-293000D01*
G01X-327050D02*
Y-281750D01*
X-332883Y-268000D01*
G01X-321217D02*
X-327050Y-281750D01*
G01X-285775Y-289667D02*
X-283442Y-291750D01*
X-280817Y-293000D01*
X-278483D01*
X-276150Y-291750D01*
X-274400Y-289667D01*
X-273525Y-286750D01*
X-274108Y-283834D01*
X-275567Y-281334D01*
X-278192Y-279666D01*
X-281692Y-278833D01*
X-283733Y-277167D01*
X-284609Y-274250D01*
X-284025Y-271333D01*
X-282567Y-269250D01*
X-280525Y-268000D01*
X-278483D01*
X-276442Y-268833D01*
X-274691Y-270917D01*
G01X-259450Y-268000D02*
X-252450D01*
G01X-255950D02*
Y-293000D01*
G01X-259450D02*
X-252450D01*
G01X-238667D02*
Y-268000D01*
X-232833D01*
X-230500Y-269250D01*
X-228750Y-270917D01*
X-227291Y-273416D01*
X-226125Y-276334D01*
X-225833Y-280500D01*
X-226125Y-284667D01*
X-227291Y-287584D01*
X-228750Y-290084D01*
X-230500Y-291750D01*
X-232833Y-293000D01*
X-238667D01*
G01X-202717D02*
X-214383D01*
Y-268000D01*
X-202717D01*
G01X-207383Y-280083D02*
X-214383D01*
G01X-475063Y-293000D02*
Y-268000D01*
X-468063D01*
X-465730Y-269250D01*
X-463980Y-272167D01*
X-463397Y-275500D01*
X-463980Y-278833D01*
X-465438Y-281334D01*
X-468063Y-282584D01*
X-475063D01*
G01X-451363Y-293000D02*
Y-268000D01*
X-444072D01*
X-441738Y-269250D01*
X-440280Y-270917D01*
X-439697Y-274250D01*
X-440280Y-277584D01*
X-442030Y-279666D01*
X-444072Y-280917D01*
X-451363D01*
G01X-444072D02*
X-439697Y-293000D01*
G01X-425330Y-268000D02*
X-418330D01*
G01X-421830D02*
Y-293000D01*
G01X-425330D02*
X-418330D01*
G01X-405714D02*
Y-268000D01*
X-398130Y-288833D01*
X-390546Y-268000D01*
Y-293000D01*
G01X-381722D02*
X-374430Y-268000D01*
X-367138Y-293000D01*
G01X-369764Y-284250D02*
X-379097D01*
G01X-356563Y-293000D02*
Y-268000D01*
X-349272D01*
X-346938Y-269250D01*
X-345480Y-270917D01*
X-344897Y-274250D01*
X-345480Y-277584D01*
X-347230Y-279666D01*
X-349272Y-280917D01*
X-356563D01*
G01X-349272D02*
X-344897Y-293000D01*
G01X-327030D02*
Y-281750D01*
X-332863Y-268000D01*
G01X-321197D02*
X-327030Y-281750D01*
G01X-285755Y-289667D02*
X-283422Y-291750D01*
X-280797Y-293000D01*
X-278463D01*
X-276130Y-291750D01*
X-274380Y-289667D01*
X-273505Y-286750D01*
X-274088Y-283834D01*
X-275547Y-281334D01*
X-278172Y-279666D01*
X-281672Y-278833D01*
X-283713Y-277167D01*
X-284589Y-274250D01*
X-284005Y-271333D01*
X-282547Y-269250D01*
X-280505Y-268000D01*
X-278463D01*
X-276422Y-268833D01*
X-274671Y-270917D01*
G01X-259430Y-268000D02*
X-252430D01*
G01X-255930D02*
Y-293000D01*
G01X-259430D02*
X-252430D01*
G01X-238647D02*
Y-268000D01*
X-232813D01*
X-230480Y-269250D01*
X-228730Y-270917D01*
X-227271Y-273416D01*
X-226105Y-276334D01*
X-225813Y-280500D01*
X-226105Y-284667D01*
X-227271Y-287584D01*
X-228730Y-290084D01*
X-230480Y-291750D01*
X-232813Y-293000D01*
X-238647D01*
G01X-202697D02*
X-214363D01*
Y-268000D01*
X-202697D01*
G01X-207363Y-280083D02*
X-214363D01*
G01X370000Y-800000D02*
Y-550000D01*
X1400000D01*
G01X640000Y-800000D02*
Y-550000D01*
G01X890000D02*
Y-800000D01*
G01X1400000Y-770000D02*
X890000D01*
G01X1400000Y-720000D02*
X890000D01*
G01X1400000Y-620000D02*
X890000D01*
G01X890070Y-550070D02*
Y-500070D01*
G01X1400060Y-500080D02*
X890060D01*
G54D18*
G01X-1930084Y-565000D02*
X-1925000Y-547500D01*
X-1919916Y-565000D01*
G01X-1921747Y-558875D02*
X-1928254D01*
G01X-1923373Y-20667D02*
X-1922560Y-19792D01*
X-1921950Y-18334D01*
X-1921543Y-16291D01*
X-1921950Y-14542D01*
X-1922763Y-13375D01*
X-1924187Y-12500D01*
X-1929677D01*
Y-30000D01*
X-1922967D01*
X-1921543Y-28834D01*
X-1920730Y-27083D01*
X-1920323Y-25042D01*
X-1920730Y-23000D01*
X-1921950Y-21250D01*
X-1923373Y-20667D01*
X-1929677D01*
G01X-1920527Y526041D02*
X-1921747Y526917D01*
X-1923170Y527500D01*
X-1924797D01*
X-1926627Y526625D01*
X-1928050Y525167D01*
X-1929067Y523416D01*
X-1929880Y520500D01*
X-1930084Y517875D01*
X-1929677Y515250D01*
X-1929067Y513500D01*
X-1927847Y511750D01*
X-1926423Y510583D01*
X-1925000Y510000D01*
X-1923577D01*
X-1922153Y510583D01*
X-1920933Y511458D01*
X-1919916Y512624D01*
G01X-1929473Y1050000D02*
Y1067500D01*
X-1925407D01*
X-1923780Y1066625D01*
X-1922560Y1065458D01*
X-1921543Y1063709D01*
X-1920730Y1061666D01*
X-1920527Y1058750D01*
X-1920730Y1055833D01*
X-1921543Y1053791D01*
X-1922560Y1052041D01*
X-1923780Y1050875D01*
X-1925407Y1050000D01*
X-1929473D01*
G01X-1710000Y-830000D02*
X-1708577Y-829708D01*
X-1706950Y-828834D01*
X-1705933Y-827376D01*
X-1705527Y-825333D01*
X-1705933Y-823292D01*
X-1707153Y-821542D01*
X-1708983Y-820667D01*
X-1711017D01*
X-1712237Y-820083D01*
X-1713254Y-818625D01*
X-1713660Y-816584D01*
X-1713050Y-814542D01*
X-1711627Y-813083D01*
X-1710000Y-812500D01*
X-1708373Y-813083D01*
X-1706950Y-814542D01*
X-1706340Y-816584D01*
X-1706747Y-818625D01*
X-1707763Y-820083D01*
X-1708983Y-820667D01*
X-1711017D01*
X-1712847Y-821542D01*
X-1714067Y-823292D01*
X-1714473Y-825333D01*
X-1714067Y-827376D01*
X-1713050Y-828834D01*
X-1711423Y-829708D01*
X-1710000Y-830000D01*
G01Y1315000D02*
X-1708577Y1315292D01*
X-1706950Y1316166D01*
X-1705933Y1317624D01*
X-1705527Y1319667D01*
X-1705933Y1321708D01*
X-1707153Y1323458D01*
X-1708983Y1324333D01*
X-1711017D01*
X-1712237Y1324917D01*
X-1713254Y1326375D01*
X-1713660Y1328416D01*
X-1713050Y1330458D01*
X-1711627Y1331917D01*
X-1710000Y1332500D01*
X-1708373Y1331917D01*
X-1706950Y1330458D01*
X-1706340Y1328416D01*
X-1706747Y1326375D01*
X-1707763Y1324917D01*
X-1708983Y1324333D01*
X-1711017D01*
X-1712847Y1323458D01*
X-1714067Y1321708D01*
X-1714473Y1319667D01*
X-1714067Y1317624D01*
X-1713050Y1316166D01*
X-1711423Y1315292D01*
X-1710000Y1315000D01*
G01X-1265407Y-830000D02*
X-1265000Y-826209D01*
X-1264390Y-823000D01*
X-1263577Y-820083D01*
X-1262560Y-816875D01*
X-1260933Y-812500D01*
X-1269067D01*
G01X-1265407Y1315000D02*
X-1265000Y1318791D01*
X-1264390Y1322000D01*
X-1263577Y1324917D01*
X-1262560Y1328125D01*
X-1260933Y1332500D01*
X-1269067D01*
G01X-838863Y-822709D02*
X-837440Y-820667D01*
X-836220Y-819500D01*
X-834593Y-818917D01*
X-833170Y-819500D01*
X-832153Y-820667D01*
X-831340Y-822417D01*
X-831137Y-824458D01*
X-831340Y-826209D01*
X-832153Y-827959D01*
X-833373Y-829417D01*
X-834797Y-830000D01*
X-836423Y-829417D01*
X-837847Y-827667D01*
X-838660Y-825042D01*
X-838863Y-822125D01*
X-838457Y-818334D01*
X-837847Y-816291D01*
X-836830Y-814250D01*
X-835407Y-812792D01*
X-833983Y-812500D01*
X-832560Y-813083D01*
X-831543Y-814542D01*
G01X-838863Y1322291D02*
X-837440Y1324333D01*
X-836220Y1325500D01*
X-834593Y1326083D01*
X-833170Y1325500D01*
X-832153Y1324333D01*
X-831340Y1322583D01*
X-831137Y1320542D01*
X-831340Y1318791D01*
X-832153Y1317041D01*
X-833373Y1315583D01*
X-834797Y1315000D01*
X-836423Y1315583D01*
X-837847Y1317333D01*
X-838660Y1319958D01*
X-838863Y1322875D01*
X-838457Y1326666D01*
X-837847Y1328709D01*
X-836830Y1330750D01*
X-835407Y1332208D01*
X-833983Y1332500D01*
X-832560Y1331917D01*
X-831543Y1330458D01*
G01X-414473Y-827376D02*
X-413254Y-828834D01*
X-411830Y-829708D01*
X-410000Y-830000D01*
X-408170Y-829417D01*
X-406747Y-828250D01*
X-405730Y-826209D01*
X-405527Y-823875D01*
X-405933Y-821542D01*
X-406950Y-820083D01*
X-408373Y-818917D01*
X-409797Y-818625D01*
X-411220Y-818917D01*
X-413050Y-820083D01*
X-412440Y-812500D01*
X-406950D01*
G01X-414473Y1317624D02*
X-413254Y1316166D01*
X-411830Y1315292D01*
X-410000Y1315000D01*
X-408170Y1315583D01*
X-406747Y1316750D01*
X-405730Y1318791D01*
X-405527Y1321125D01*
X-405933Y1323458D01*
X-406950Y1324917D01*
X-408373Y1326083D01*
X-409797Y1326375D01*
X-411220Y1326083D01*
X-413050Y1324917D01*
X-412440Y1332500D01*
X-406950D01*
G01X22440Y-830000D02*
Y-812500D01*
X14916Y-825042D01*
X25084D01*
G01X22440Y1315000D02*
Y1332500D01*
X14916Y1319958D01*
X25084D01*
G01X435527Y-826500D02*
X436746Y-828542D01*
X438373Y-829708D01*
X440203Y-830000D01*
X441830Y-829708D01*
X443457Y-828250D01*
X444473Y-826500D01*
X444677Y-824750D01*
X444270Y-822709D01*
X442847Y-821250D01*
X441423Y-820667D01*
X439593D01*
G01X441423D02*
X442643Y-819792D01*
X443660Y-818334D01*
X444067Y-816584D01*
X443660Y-814833D01*
X442643Y-813375D01*
X440813Y-812500D01*
X438983Y-812792D01*
X437153Y-813959D01*
G01X435527Y1318500D02*
X436746Y1316458D01*
X438373Y1315292D01*
X440203Y1315000D01*
X441830Y1315292D01*
X443457Y1316750D01*
X444473Y1318500D01*
X444677Y1320250D01*
X444270Y1322291D01*
X442847Y1323750D01*
X441423Y1324333D01*
X439593D01*
G01X441423D02*
X442643Y1325208D01*
X443660Y1326666D01*
X444067Y1328416D01*
X443660Y1330167D01*
X442643Y1331625D01*
X440813Y1332500D01*
X438983Y1332208D01*
X437153Y1331041D01*
G01X866137Y-815417D02*
X867357Y-813667D01*
X868780Y-812792D01*
X870407Y-812500D01*
X872440Y-813083D01*
X873863Y-814542D01*
X874270Y-816291D01*
X874067Y-818042D01*
X873253Y-819500D01*
X869187Y-822417D01*
X867357Y-824458D01*
X866137Y-827376D01*
X865730Y-830000D01*
X874270D01*
G01X866137Y1329583D02*
X867357Y1331333D01*
X868780Y1332208D01*
X870407Y1332500D01*
X872440Y1331917D01*
X873863Y1330458D01*
X874270Y1328709D01*
X874067Y1326958D01*
X873253Y1325500D01*
X869187Y1322583D01*
X867357Y1320542D01*
X866137Y1317624D01*
X865730Y1315000D01*
X874270D01*
G01X931770Y-566600D02*
X923460Y-604100D01*
X933630D01*
X940050Y-578300D01*
X940620Y-604100D01*
X947610D01*
X960900Y-578630D01*
X955140Y-604100D01*
X965430D01*
X973740Y-566600D01*
X959190D01*
X947190Y-590480D01*
X946680Y-566600D01*
X931770D01*
G01X943650Y-603500D02*
X949050Y-592400D01*
X948300Y-591800D01*
X942150Y-603050D01*
X941700Y-600050D01*
X947250Y-591350D01*
X942450Y-600200D01*
X941250Y-597950D01*
X946650Y-590600D01*
X945600Y-570950D01*
X945450Y-568100D01*
X932850D01*
X924900Y-602750D01*
X932400D01*
X939300Y-577250D01*
X940500Y-577100D01*
X941850Y-596000D01*
X945450Y-590000D01*
X944100Y-569450D01*
X933750Y-569600D01*
X926400Y-601400D01*
X931350D01*
X938550Y-575450D01*
X941100Y-575750D01*
X942750Y-592700D01*
X944100Y-589700D01*
X942900Y-570800D01*
X934500Y-570950D01*
X928050Y-600200D01*
X930300Y-600350D01*
X937500Y-574700D01*
X941700D01*
X943200Y-586550D01*
X941700Y-572000D01*
X935250Y-572450D01*
X929550Y-599150D01*
X936450Y-573350D01*
X940800D01*
G01X972300Y-567500D02*
X964350Y-602600D01*
X956850Y-602750D01*
X957000Y-601100D01*
X963300Y-601400D01*
X964050Y-599750D01*
X957150Y-599900D01*
X957450Y-598250D01*
X964050D01*
X964800Y-597050D01*
X958050Y-596900D01*
X958200Y-595400D01*
X964950D01*
X965400Y-593900D01*
X958350Y-594050D01*
X958650Y-592700D01*
X965550Y-592550D01*
X966000Y-591050D01*
X958950Y-591200D01*
X959400Y-589550D01*
X966450Y-589700D01*
X967050Y-587900D01*
X958950Y-588500D01*
X960000Y-587000D01*
X966750Y-587150D01*
X967500Y-585800D01*
X960150D01*
X960600Y-584150D01*
X967350Y-584450D01*
X967800Y-583100D01*
X961200D01*
X961350Y-582050D01*
X967800D01*
X968550Y-581000D01*
X961500Y-580850D01*
X961650Y-579950D01*
X968400Y-580100D01*
X968700Y-579050D01*
X962250Y-578750D01*
X961350Y-578000D01*
X969300D01*
X969750Y-576500D01*
X971100Y-567950D01*
X960000D01*
X959250Y-569300D01*
X969600D01*
X969300Y-570800D01*
X958500Y-570650D01*
X957900Y-571850D01*
X969150Y-572000D01*
X969300Y-573500D01*
X957150Y-573050D01*
X956700Y-574100D01*
X969000Y-574700D01*
X968550Y-576200D01*
X956100Y-575450D01*
X967650Y-577100D01*
X955500Y-576650D01*
X960750Y-577850D01*
X955050Y-577700D01*
X948450Y-591050D01*
X952200Y-592850D01*
X959250Y-579050D01*
X955650Y-578900D01*
X950100Y-591050D01*
X951750Y-591500D01*
X957000Y-579950D01*
G01X951750Y-593600D02*
X946800Y-602750D01*
G01X950550Y-592700D02*
X945000Y-603650D01*
G01X975870Y-576800D02*
X969690Y-604100D01*
X978930D01*
X984840Y-576800D01*
X975870D01*
G01X976800Y-577850D02*
X971100Y-602900D01*
X977700Y-602750D01*
X983550Y-578150D01*
X981750D01*
X976650Y-601250D01*
X972600Y-601700D01*
X977850Y-578000D01*
X980400Y-577850D01*
X975600Y-600050D01*
X974250Y-600350D01*
X978900Y-579050D01*
G01X1006050Y-586100D02*
Y-585380D01*
X1005540Y-583610D01*
X1004550Y-582050D01*
X1003200Y-581600D01*
X1001130D01*
X998910Y-582980D01*
X996960Y-584750D01*
X995640Y-586580D01*
X994680Y-589130D01*
X994050Y-591320D01*
X993750Y-593840D01*
Y-595280D01*
X994470Y-597080D01*
X996330Y-599300D01*
X1000260D01*
X1002240Y-597500D01*
X1003530Y-595550D01*
X1003590Y-595400D01*
X1013730D01*
X1013640Y-595610D01*
X1012740Y-597260D01*
X1012470Y-597950D01*
X1011390Y-599300D01*
X1010250Y-600440D01*
X1008510Y-601880D01*
X1006770Y-603050D01*
X1005390Y-603860D01*
X1001430Y-605000D01*
X993540D01*
X992190Y-604730D01*
X989670Y-603890D01*
X988650Y-603110D01*
X986640Y-601100D01*
X985830Y-600020D01*
X985590Y-599570D01*
X985020Y-597740D01*
X984750Y-596210D01*
Y-590420D01*
X985590Y-587060D01*
X986430Y-585620D01*
X987030Y-584420D01*
X987870Y-583070D01*
X990450Y-580460D01*
X991890Y-579320D01*
X993000Y-578480D01*
X995640Y-577310D01*
X996750Y-576740D01*
X997800Y-576470D01*
X1000110Y-576200D01*
X1004520D01*
X1007970Y-576500D01*
X1009590Y-577040D01*
X1010130Y-577280D01*
X1012110Y-578420D01*
X1012590Y-578900D01*
X1014270Y-580880D01*
X1015410Y-583700D01*
X1015650Y-584450D01*
Y-586100D01*
X1006050D01*
G01X1011900Y-596600D02*
X1008300Y-601100D01*
X1001250Y-603800D01*
X992850Y-603650D01*
X989100Y-601700D01*
X987300Y-599750D01*
X986400Y-597500D01*
X985950Y-594650D01*
X986250Y-590150D01*
X987900Y-585050D01*
X990750Y-581900D01*
X995700Y-578600D01*
X1001850Y-577550D01*
X1007550Y-577850D01*
X1011900Y-580100D01*
X1014750Y-584600D01*
X1007250Y-584750D01*
X1005900Y-582050D01*
X1003350Y-580400D01*
X1000800Y-580250D01*
X998100Y-581600D01*
X995550Y-584300D01*
X993300Y-588650D01*
X992400Y-593150D01*
X993750Y-598850D01*
X995700Y-600500D01*
X998550Y-600650D01*
X1001550Y-600350D01*
X1004250Y-596900D01*
X1010550Y-596750D01*
X1007250Y-600050D01*
X1003650Y-601250D01*
X1000200Y-602450D01*
X992550Y-602300D01*
X988650Y-599150D01*
X987300Y-594350D01*
X987750Y-590900D01*
X988950Y-586250D01*
X991050Y-583550D01*
X996300Y-579800D01*
X1002900Y-578750D01*
X1009050Y-579650D01*
X1012800Y-583400D01*
X1007850D01*
X1004550Y-580100D01*
X1010850Y-581450D01*
X1011750Y-582350D01*
X1007100Y-581750D01*
G01X999150Y-580250D02*
X995550Y-581900D01*
X992250Y-584600D01*
X990150Y-587150D01*
X988800Y-594650D01*
X989700Y-598250D01*
X994500Y-601700D01*
X1001400Y-601550D01*
X1008600Y-597650D01*
X1002900Y-598850D01*
X994350Y-600350D01*
X992850Y-599300D01*
X991950Y-596750D01*
X991350Y-593900D01*
X991950Y-589400D01*
X995250Y-583100D01*
X990900Y-588800D01*
X990600Y-591800D01*
X990150Y-594800D01*
X991500Y-598100D01*
G01X977970Y-566600D02*
X977010Y-571100D01*
X986430D01*
X987390Y-566600D01*
X977970D01*
G01X978600Y-568400D02*
X985950Y-568250D01*
X985500Y-569750D01*
X978450D01*
G01X1034910Y-584390D02*
X1033740Y-584630D01*
X1032390Y-584960D01*
X1030680Y-585980D01*
X1029450Y-587210D01*
X1028070Y-588260D01*
X1027740Y-589280D01*
X1026840Y-590480D01*
X1026510Y-591470D01*
X1025910Y-592670D01*
X1025580Y-593690D01*
X1025280Y-595790D01*
X1024980Y-596660D01*
X1024680Y-598160D01*
X1024380Y-599060D01*
X1023450Y-602720D01*
X1023270Y-604100D01*
X1014540D01*
X1015620Y-599840D01*
X1015920Y-598910D01*
X1016250Y-596450D01*
X1016520Y-595040D01*
X1016820Y-594140D01*
X1017120Y-592640D01*
X1017420Y-591740D01*
X1018050Y-589250D01*
X1018320Y-586580D01*
X1018620Y-585740D01*
X1018920Y-584240D01*
X1019220Y-583340D01*
X1020420Y-578450D01*
X1020630Y-576800D01*
X1029180D01*
X1028850Y-577490D01*
Y-581360D01*
X1031250Y-578990D01*
X1032330Y-578180D01*
X1033980Y-577340D01*
X1035660Y-576770D01*
X1037310Y-576500D01*
X1038420D01*
X1037310Y-580910D01*
X1034910Y-584390D01*
G01X1035750Y-582050D02*
X1020750Y-582200D01*
X1020450Y-583400D01*
X1034550Y-583250D01*
X1031250Y-584450D01*
X1019700Y-584750D01*
X1019400Y-586100D01*
X1029600Y-585950D01*
X1027800Y-587450D01*
X1019250Y-587300D01*
X1019100Y-588650D01*
X1027050Y-588800D01*
X1025850Y-590450D01*
X1018500Y-590150D01*
Y-591500D01*
X1025100Y-591800D01*
X1024800Y-593300D01*
X1018050Y-593000D01*
X1017750Y-594350D01*
X1024500Y-594650D01*
X1024200Y-596300D01*
X1017600Y-595850D01*
X1017150Y-596900D01*
X1023750Y-597500D01*
X1023450Y-599300D01*
X1016850Y-598250D01*
X1016700Y-599300D01*
X1023150Y-600050D01*
X1022850Y-601250D01*
X1016550Y-600800D01*
X1015950Y-601700D01*
X1022850Y-602300D01*
X1022700Y-602900D01*
X1015800Y-603050D01*
G01X1021350Y-578000D02*
X1027650Y-578150D01*
X1027800Y-579650D01*
X1021350Y-579500D01*
X1021050Y-581000D01*
X1036350Y-580850D01*
X1037100Y-577850D01*
X1031850Y-579650D01*
X1035750D01*
G01X1042100Y-682500D02*
Y-700000D01*
G01X1037423Y-682500D02*
X1046777D01*
G01X1054633Y-700000D02*
Y-682500D01*
X1059717D01*
X1061343Y-683375D01*
X1062360Y-684542D01*
X1062767Y-686875D01*
X1062360Y-689208D01*
X1061140Y-690667D01*
X1059717Y-691542D01*
X1054633D01*
G01X1059717D02*
X1062767Y-700000D01*
G01X1070216D02*
X1075300Y-682500D01*
X1080384Y-700000D01*
G01X1078553Y-693875D02*
X1072046D01*
G01X1091900Y-700000D02*
Y-692125D01*
X1087833Y-682500D01*
G01X1095967D02*
X1091900Y-692125D01*
G01X1126727Y-690667D02*
X1127540Y-689792D01*
X1128150Y-688334D01*
X1128557Y-686291D01*
X1128150Y-684542D01*
X1127337Y-683375D01*
X1125913Y-682500D01*
X1120423D01*
Y-700000D01*
X1127133D01*
X1128557Y-698834D01*
X1129370Y-697083D01*
X1129777Y-695042D01*
X1129370Y-693000D01*
X1128150Y-691250D01*
X1126727Y-690667D01*
X1120423D01*
G01X1136616Y-700000D02*
X1141700Y-682500D01*
X1146784Y-700000D01*
G01X1144953Y-693875D02*
X1138446D01*
G01X1162773Y-683959D02*
X1161553Y-683083D01*
X1160130Y-682500D01*
X1158503D01*
X1156673Y-683375D01*
X1155250Y-684833D01*
X1154233Y-686584D01*
X1153420Y-689500D01*
X1153216Y-692125D01*
X1153623Y-694750D01*
X1154233Y-696500D01*
X1155453Y-698250D01*
X1156877Y-699417D01*
X1158300Y-700000D01*
X1159723D01*
X1161147Y-699417D01*
X1162367Y-698542D01*
X1163384Y-697376D01*
G01X1170427Y-700000D02*
Y-682500D01*
G01X1178153D02*
X1170427Y-693292D01*
G01X1179373Y-700000D02*
X1173883Y-688334D01*
G01X1187433Y-700000D02*
Y-682500D01*
X1192313D01*
X1193940Y-683375D01*
X1195160Y-685417D01*
X1195567Y-687750D01*
X1195160Y-690083D01*
X1194143Y-691833D01*
X1192313Y-692709D01*
X1187433D01*
G01X1204033Y-682500D02*
Y-700000D01*
X1212167D01*
G01X1219616D02*
X1224700Y-682500D01*
X1229784Y-700000D01*
G01X1227953Y-693875D02*
X1221446D01*
G01X1236623Y-700000D02*
Y-682500D01*
X1245977Y-700000D01*
Y-682500D01*
G01X1261967Y-700000D02*
X1253833D01*
Y-682500D01*
X1261967D01*
G01X1258713Y-690958D02*
X1253833D01*
G01X1037190Y-583940D02*
X1039980Y-580460D01*
X1041090Y-579620D01*
X1042500Y-578510D01*
X1043280Y-578240D01*
X1044090Y-577850D01*
X1044390Y-577550D01*
X1044780Y-577340D01*
X1045680Y-577040D01*
X1046280Y-576740D01*
X1047060Y-576470D01*
X1049100Y-576200D01*
X1050840Y-575900D01*
X1054590D01*
X1058640Y-576470D01*
X1059420Y-576740D01*
X1060470Y-577280D01*
X1061730Y-578210D01*
X1062570Y-578480D01*
X1062690Y-578600D01*
X1064700Y-580910D01*
X1065510Y-582530D01*
X1065810Y-583400D01*
X1066350Y-584780D01*
Y-589850D01*
X1065870Y-591290D01*
X1064550Y-591530D01*
X1063920Y-591860D01*
X1063020Y-592160D01*
X1061820Y-592760D01*
X1060920Y-593060D01*
X1060350Y-593330D01*
X1058850Y-593630D01*
X1058220Y-593960D01*
X1057260Y-594290D01*
X1054230Y-596300D01*
X1064010D01*
X1063170Y-597950D01*
X1062660Y-598730D01*
X1059780Y-601580D01*
X1056090Y-603860D01*
X1052130Y-605000D01*
X1042800D01*
X1042050Y-604760D01*
X1039170Y-603590D01*
X1038420Y-603110D01*
X1036140Y-600830D01*
X1035660Y-600110D01*
X1035360Y-599240D01*
X1034790Y-598220D01*
X1034520Y-596930D01*
X1034250Y-596270D01*
Y-590720D01*
X1034520Y-589640D01*
X1034790Y-588830D01*
X1035090Y-588230D01*
X1035420Y-587240D01*
X1035660Y-586250D01*
X1038180Y-583730D01*
X1037190Y-583940D01*
G01X1057050Y-592850D02*
X1065300Y-589850D01*
X1065150Y-584900D01*
X1063800Y-581750D01*
X1060800Y-579200D01*
X1056000Y-577400D01*
X1051800Y-577100D01*
X1046550Y-577700D01*
X1041600Y-580400D01*
X1038900Y-584000D01*
X1036650Y-587150D01*
X1035600Y-591650D01*
X1035750Y-596900D01*
X1037850Y-601100D01*
X1041600Y-603200D01*
X1047450Y-603950D01*
X1054500Y-603350D01*
X1058700Y-600950D01*
X1061100Y-598400D01*
X1062000Y-597500D01*
X1054800Y-597800D01*
X1052550Y-599900D01*
X1059150Y-598850D01*
X1055550Y-600950D01*
X1051200Y-600350D01*
X1055100Y-602150D01*
X1051500D01*
X1050450Y-601100D01*
X1050900Y-602750D01*
X1049100Y-601100D01*
X1046700D01*
X1049850Y-602900D01*
X1045200Y-602300D01*
X1040850Y-601400D01*
X1038750Y-599600D01*
X1037100Y-596150D01*
X1036950Y-592250D01*
X1037400Y-588800D01*
X1038900Y-585650D01*
X1041600Y-582500D01*
X1043850Y-580550D01*
X1047150Y-579050D01*
X1052700Y-578300D01*
X1056600Y-579200D01*
X1060500Y-580850D01*
X1062750Y-582500D01*
X1064100Y-586100D01*
X1064250Y-589100D01*
X1057800Y-591050D01*
X1058100Y-589250D01*
X1063350Y-587900D01*
X1063050Y-586250D01*
X1058250Y-587750D01*
X1058100Y-585800D01*
X1062600Y-585200D01*
X1062150Y-583550D01*
X1058400Y-584300D01*
X1057650Y-583100D01*
X1061100Y-582350D01*
X1060350Y-581600D01*
X1056900Y-581750D01*
X1057800Y-581000D01*
X1055100Y-580250D01*
X1052400Y-579350D01*
X1049700Y-579500D01*
X1046700Y-580400D01*
X1044150Y-581750D01*
X1040250Y-586550D01*
X1038300Y-590450D01*
Y-594800D01*
X1039950Y-598700D01*
X1042950Y-601250D01*
X1046100Y-601100D01*
X1044150Y-598700D01*
X1042650Y-596300D01*
Y-591500D01*
X1044150Y-586700D01*
X1046250Y-583100D01*
X1049850Y-580550D01*
X1044000Y-583250D01*
X1043850Y-585500D01*
X1042950Y-585050D01*
X1040550Y-588650D01*
X1039500Y-592250D01*
X1039950Y-595400D01*
X1041750Y-599150D01*
X1044450Y-600350D01*
X1042050Y-596900D01*
X1041300Y-594650D01*
X1043100Y-586550D01*
X1040400Y-593450D01*
G01X1035600Y-584600D02*
X1037850Y-581750D01*
G01X1048350Y-599900D02*
X1049910D01*
X1050330Y-599480D01*
X1051200Y-599210D01*
X1052880Y-597860D01*
X1054800Y-595610D01*
X1055430Y-594350D01*
X1055730Y-593900D01*
X1056060Y-593240D01*
X1056690Y-591830D01*
X1057020Y-590840D01*
X1057350Y-589520D01*
Y-585080D01*
X1056960Y-583550D01*
X1056510Y-583100D01*
X1054950Y-581210D01*
X1054170Y-580700D01*
X1050990D01*
X1050450Y-581210D01*
X1048050Y-583010D01*
X1047360Y-583730D01*
X1046730Y-584660D01*
X1045410Y-586280D01*
X1045110Y-587570D01*
X1044510Y-588740D01*
X1043850Y-590750D01*
Y-596210D01*
X1044570Y-597650D01*
X1045290Y-598760D01*
X1047030Y-599900D01*
X1048350D01*
G01X1065330Y-596300D02*
X1075350D01*
Y-597860D01*
X1075800Y-598340D01*
X1076220Y-599150D01*
X1077270Y-599480D01*
X1077510Y-599750D01*
X1078320Y-600140D01*
X1079400Y-600500D01*
X1082460D01*
X1085190Y-599150D01*
X1085850Y-598460D01*
Y-597920D01*
X1086240Y-597320D01*
X1085430Y-594860D01*
X1083840Y-593660D01*
X1082160Y-593330D01*
X1077390Y-592130D01*
X1075590Y-591530D01*
X1074600Y-591290D01*
X1074390Y-591050D01*
X1073190Y-590450D01*
X1072290Y-589550D01*
X1071690Y-589250D01*
X1071300Y-588860D01*
X1071000Y-588260D01*
X1070730Y-588020D01*
X1070250Y-586550D01*
Y-582950D01*
X1070520Y-582140D01*
X1070790Y-581000D01*
X1071000Y-580640D01*
X1072500Y-579140D01*
X1072710Y-578660D01*
X1077120Y-576470D01*
X1080570Y-575900D01*
X1082910Y-575600D01*
X1085220D01*
X1088130Y-575900D01*
X1091640Y-576470D01*
X1093320Y-577040D01*
X1093800Y-577280D01*
X1095480Y-578390D01*
X1096260Y-579200D01*
X1097070Y-580280D01*
X1097250Y-580610D01*
Y-583700D01*
X1088250D01*
Y-582050D01*
X1086630Y-580820D01*
X1085760Y-580400D01*
X1082430D01*
X1081080Y-580790D01*
X1079970Y-581660D01*
X1079490Y-583100D01*
X1079910Y-584330D01*
X1080390Y-585260D01*
X1083210Y-586670D01*
X1086900Y-587000D01*
X1088010Y-587270D01*
X1088850Y-587540D01*
X1091250Y-588440D01*
X1093020Y-589040D01*
X1093410Y-589250D01*
X1095270Y-591080D01*
X1095780Y-592640D01*
X1096050Y-593990D01*
Y-595880D01*
X1095210Y-599300D01*
X1095000Y-599690D01*
X1093290Y-601700D01*
X1093080Y-601910D01*
X1091100Y-603320D01*
X1090020Y-603860D01*
X1086600Y-605000D01*
X1073640D01*
X1072260Y-604730D01*
X1071120Y-604430D01*
X1069710Y-603890D01*
X1068660Y-603350D01*
X1066950Y-601940D01*
X1066230Y-601220D01*
X1065990Y-600470D01*
X1065720Y-599900D01*
X1065450Y-598730D01*
X1065330Y-596300D01*
G01X1063350D02*
X1066800D01*
G01X1066350Y-597350D02*
X1074150Y-597800D01*
X1076250Y-600350D01*
X1080900Y-601700D01*
X1084500Y-601250D01*
X1087050Y-599150D01*
X1087500Y-596600D01*
X1086750Y-594800D01*
X1085550Y-593150D01*
X1083300Y-592250D01*
X1081050Y-591500D01*
X1078050Y-590750D01*
X1074150Y-589250D01*
X1072350Y-588050D01*
X1071300Y-584750D01*
X1071750Y-581750D01*
X1073100Y-579800D01*
X1076250Y-578300D01*
X1079100Y-577400D01*
X1083150Y-577100D01*
X1086150Y-576950D01*
X1090650Y-577700D01*
X1093500Y-578750D01*
X1095450Y-580250D01*
X1096050Y-582350D01*
X1089600Y-582500D01*
X1088850Y-581450D01*
X1094550Y-581000D01*
X1094100Y-579950D01*
X1088700Y-580550D01*
X1092000Y-579350D01*
X1087350Y-579800D01*
X1090350Y-578600D01*
X1085850Y-579200D01*
X1087200Y-578150D01*
X1081350Y-578450D01*
X1085100Y-579200D01*
X1080900Y-579800D01*
X1080600Y-578750D01*
X1074150Y-580850D01*
X1080000Y-580400D01*
X1073100Y-581900D01*
X1072800Y-585500D01*
X1074450Y-588650D01*
X1079400Y-589700D01*
X1084200Y-591350D01*
X1087800Y-594200D01*
X1088550Y-599000D01*
X1086150Y-602150D01*
X1080750Y-603200D01*
X1077600Y-602150D01*
X1072800Y-599000D01*
X1067100Y-598550D01*
X1067850Y-600950D01*
X1068450Y-600200D01*
X1072050Y-600500D01*
X1069050Y-601700D01*
X1072950Y-600650D01*
X1080000Y-603500D01*
X1072350D01*
X1069500Y-602600D01*
X1075200Y-602450D01*
X1081950Y-603800D01*
X1087500Y-603650D01*
X1091250Y-601700D01*
X1093950Y-599150D01*
X1094550Y-594200D01*
X1093800Y-591200D01*
X1087800Y-588650D01*
X1083600Y-587600D01*
X1080900Y-587000D01*
X1078800Y-585500D01*
X1078500Y-581600D01*
X1073850Y-582950D01*
X1075200Y-587300D01*
X1078500Y-588350D01*
X1083000Y-589400D01*
X1086600Y-590900D01*
X1088700Y-593000D01*
X1089450Y-596000D01*
X1089750Y-598400D01*
X1087200Y-602450D01*
X1090800Y-600350D01*
X1093050Y-598250D01*
X1090050Y-599600D01*
X1093500Y-596450D01*
X1093200Y-592400D01*
X1081950Y-587300D01*
X1079700Y-587600D01*
X1076100Y-585950D01*
X1075200Y-583700D01*
X1077300Y-582950D01*
X1076100Y-584750D01*
X1078050Y-583850D01*
X1077600Y-585350D01*
X1090950Y-593000D01*
X1092150Y-593900D01*
X1092450Y-595850D01*
X1090800Y-597500D01*
X1089300Y-592550D01*
X1092150Y-596450D01*
G01X1117050Y-579800D02*
X1117350Y-576650D01*
X1123200Y-577700D01*
X1126950Y-580100D01*
X1129350Y-584450D01*
X1129650Y-591050D01*
X1126650Y-597350D01*
X1123050Y-601100D01*
X1117500Y-603500D01*
X1106550Y-603200D01*
X1100550Y-596300D01*
X1100400Y-590150D01*
X1102200Y-584900D01*
X1108500Y-579050D01*
X1113000Y-577550D01*
X1119600Y-577700D01*
X1126500Y-581300D01*
X1128450Y-586550D01*
X1128000Y-591800D01*
X1125900Y-596150D01*
X1122450Y-599750D01*
X1117650Y-602150D01*
X1110450Y-602750D01*
X1107150Y-603650D01*
X1103550Y-602600D01*
X1100100Y-597200D01*
X1108350Y-602150D01*
X1114800Y-601550D01*
X1120200Y-599300D01*
X1123200Y-596900D01*
X1126050Y-593000D01*
X1127250Y-588350D01*
X1126650Y-583400D01*
X1120500Y-579350D01*
X1117950Y-579050D01*
X1120500Y-581000D01*
X1123350Y-582950D01*
X1125300Y-584600D01*
X1125900Y-587900D01*
X1125600Y-591650D01*
X1123800Y-594500D01*
X1121400Y-597050D01*
X1118250Y-598550D01*
X1115700Y-599300D01*
X1113750Y-600350D01*
X1111050Y-600650D01*
X1107900Y-600500D01*
X1102500Y-597200D01*
X1101600Y-592850D01*
X1101450Y-588800D01*
X1103100Y-585050D01*
X1105950Y-582050D01*
X1110150Y-579650D01*
X1114350Y-578750D01*
X1116600D01*
X1115700Y-579500D01*
X1111050Y-580250D01*
X1108050Y-582500D01*
X1105650Y-584150D01*
X1104150Y-586400D01*
X1102800Y-589700D01*
X1102950Y-593600D01*
X1103700Y-596900D01*
X1105650Y-598550D01*
X1109550Y-599600D01*
X1107450Y-597200D01*
X1107300Y-592100D01*
X1108050Y-587600D01*
X1114200Y-580550D01*
X1110600Y-581600D01*
X1106400Y-585200D01*
X1104300Y-589550D01*
Y-594050D01*
X1104900Y-597200D01*
X1106550Y-597800D01*
X1105350Y-592850D01*
X1106100Y-588350D01*
X1108950Y-583250D01*
X1112100Y-581450D01*
X1108050Y-585800D01*
X1105950Y-594350D01*
G01X1114740Y-575900D02*
X1120260D01*
X1123110Y-576470D01*
X1123890Y-576710D01*
X1125930Y-577880D01*
X1127010Y-578450D01*
X1127970Y-579380D01*
X1128270Y-580280D01*
X1129200Y-581240D01*
X1129500Y-581840D01*
X1129740Y-582050D01*
X1129950Y-582920D01*
Y-583460D01*
X1130400Y-583940D01*
X1130580Y-584270D01*
X1130850Y-585860D01*
Y-589610D01*
X1130580Y-590990D01*
X1130280Y-592220D01*
X1129980Y-593930D01*
X1129170Y-595520D01*
X1128240Y-596780D01*
X1127940Y-597650D01*
X1126890Y-599000D01*
X1124280Y-601610D01*
X1123500Y-602120D01*
X1122870Y-602420D01*
X1121670Y-603320D01*
X1120620Y-603860D01*
X1116930Y-605000D01*
X1107600D01*
X1104210Y-603860D01*
X1103760Y-603650D01*
X1101750Y-601940D01*
X1101270Y-601430D01*
X1100430Y-600050D01*
X1099290Y-598040D01*
X1099050Y-597350D01*
Y-590120D01*
X1099320Y-589070D01*
X1099890Y-587600D01*
X1100190Y-586730D01*
X1101030Y-584750D01*
X1102740Y-582500D01*
X1105650Y-579590D01*
X1106730Y-578780D01*
X1107900Y-578180D01*
X1109340Y-577310D01*
X1110750Y-576740D01*
X1111590Y-576470D01*
X1114740Y-575900D01*
G01X1119300Y-581120D02*
X1120500Y-581930D01*
X1120860Y-583010D01*
X1121490Y-583940D01*
X1121850Y-585710D01*
Y-588890D01*
X1121520Y-590540D01*
X1120920Y-592340D01*
X1120590Y-593630D01*
X1120200Y-594440D01*
X1119540Y-595070D01*
X1118940Y-595970D01*
X1116060Y-598880D01*
X1114470Y-599510D01*
X1113870Y-599900D01*
X1111920D01*
X1110990Y-599510D01*
X1110210Y-599150D01*
X1109460Y-598370D01*
X1108770Y-597350D01*
X1108350Y-596510D01*
Y-590630D01*
X1108680Y-589430D01*
X1109370Y-587420D01*
X1109760Y-587030D01*
X1110570Y-585800D01*
X1111200Y-584510D01*
X1112250Y-583460D01*
X1112820Y-583040D01*
X1113420Y-582290D01*
X1115100Y-581120D01*
X1115940Y-580700D01*
X1118460D01*
X1119300Y-581120D01*
G01X1131630Y-581900D02*
X1132890Y-576800D01*
X1138650D01*
Y-575420D01*
X1138920Y-574340D01*
X1139490Y-572630D01*
X1140090Y-571430D01*
X1140390Y-570530D01*
X1140600Y-570140D01*
X1142490Y-568250D01*
X1142880Y-568040D01*
X1145130Y-567470D01*
X1146840Y-567200D01*
X1151790D01*
X1152840Y-567350D01*
X1152780Y-567560D01*
X1152480Y-568790D01*
X1152180Y-570170D01*
X1152000Y-571100D01*
X1150890D01*
X1150410Y-571550D01*
X1149210Y-572150D01*
X1148670Y-572720D01*
X1148280Y-573860D01*
X1147560Y-576800D01*
X1154970D01*
X1155420Y-575870D01*
X1155750Y-573350D01*
X1156590Y-569900D01*
X1165110D01*
X1165080Y-570020D01*
X1164780Y-572420D01*
X1164210Y-574670D01*
X1163850Y-575390D01*
Y-576800D01*
X1168800D01*
X1168680Y-577160D01*
X1168380Y-578660D01*
X1168080Y-579560D01*
X1167780Y-581090D01*
X1167570Y-581900D01*
X1162350D01*
Y-583250D01*
X1162080Y-584060D01*
X1161780Y-585560D01*
X1161480Y-586460D01*
X1161180Y-587690D01*
X1160850Y-589250D01*
X1160580Y-591590D01*
X1160280Y-592460D01*
X1159980Y-593960D01*
X1159680Y-594860D01*
X1159440Y-595850D01*
X1159050Y-596240D01*
Y-597950D01*
X1160550Y-599090D01*
X1161090Y-599600D01*
X1163670D01*
X1162980Y-602420D01*
X1162680Y-604430D01*
Y-604460D01*
X1159920Y-604700D01*
X1156710D01*
X1154430Y-604430D01*
X1152210Y-603860D01*
X1151040Y-603170D01*
X1150560Y-602240D01*
X1150350Y-601670D01*
Y-598490D01*
X1150620Y-597140D01*
X1150950Y-596210D01*
X1151250Y-593510D01*
X1151520Y-592640D01*
X1151820Y-591140D01*
X1152120Y-590240D01*
X1152420Y-588740D01*
X1152720Y-587840D01*
X1153020Y-586340D01*
X1153320Y-585410D01*
X1153770Y-581900D01*
X1146150D01*
Y-583580D01*
X1145580Y-585920D01*
X1145280Y-588320D01*
X1144080Y-593060D01*
X1143780Y-593960D01*
X1143450Y-595550D01*
X1143180Y-597890D01*
X1142880Y-598760D01*
X1142580Y-600290D01*
X1142280Y-601460D01*
X1141980Y-602360D01*
X1141680Y-603860D01*
X1141590Y-604100D01*
X1132290D01*
X1133550Y-599180D01*
X1133850Y-596780D01*
X1134120Y-595640D01*
X1134420Y-594740D01*
X1134720Y-593240D01*
X1135020Y-592340D01*
X1135320Y-590840D01*
X1135620Y-589940D01*
X1135950Y-588350D01*
X1136250Y-586280D01*
X1136790Y-584000D01*
X1137150Y-583310D01*
Y-581900D01*
X1131630D01*
G01X1118550Y-597350D02*
X1122900Y-593900D01*
X1125150Y-588800D01*
X1124400Y-585050D01*
X1122150Y-583100D01*
X1123800Y-588500D01*
X1122900Y-588650D01*
X1124100Y-590000D01*
X1122450D01*
X1122900Y-591200D01*
X1121700Y-593450D01*
G01X1151100Y-568100D02*
X1150800Y-570200D01*
X1148100Y-571850D01*
X1146300Y-577400D01*
X1155450Y-578000D01*
X1157550Y-571400D01*
X1163400Y-571250D01*
X1162650Y-576350D01*
X1165200Y-578150D01*
X1167150Y-578450D01*
X1166700Y-580550D01*
X1161000Y-580850D01*
X1158300Y-596600D01*
X1160400Y-600800D01*
X1161900D01*
X1161600Y-603200D01*
X1156350Y-603350D01*
X1151850Y-602450D01*
X1151700Y-599000D01*
X1152150Y-593900D01*
X1154400Y-585350D01*
X1155300Y-581450D01*
X1155750Y-580850D01*
X1153500Y-580550D01*
X1146600D01*
X1144800Y-580700D01*
X1140600Y-603050D01*
X1134000Y-602750D01*
X1138350Y-582350D01*
X1138650Y-580850D01*
X1132950D01*
X1133850Y-578150D01*
X1138650Y-577850D01*
X1138200Y-579800D01*
X1134600Y-579500D01*
X1166250D01*
G01X1145550Y-581900D02*
X1143900Y-590450D01*
G01X1138800Y-580550D02*
X1143900D01*
X1139550Y-602300D01*
X1134900Y-601700D01*
X1139850Y-581450D01*
X1142400Y-581900D01*
X1138350Y-601100D01*
X1136250D01*
X1140900Y-582800D01*
X1137600Y-600500D01*
G01X1149750Y-567950D02*
X1149300Y-569750D01*
X1148250Y-568400D01*
X1143000Y-569300D01*
X1141350Y-571700D01*
X1139850Y-575900D01*
X1139700Y-578150D01*
X1151100Y-578450D01*
G01X1148400Y-569900D02*
X1145100Y-576950D01*
X1141050D01*
X1143900Y-570200D01*
X1147650Y-569750D01*
X1144200Y-575750D01*
X1143000Y-575900D01*
X1145250Y-571250D01*
G01X1158000Y-572600D02*
X1162050D01*
X1164000Y-578750D01*
X1161750Y-573650D01*
X1162350Y-579200D01*
X1156800Y-602450D01*
X1160700Y-602150D01*
G01X1159350Y-602000D02*
X1158900Y-599600D01*
X1158150Y-601550D01*
X1153200D01*
Y-594650D01*
X1158000Y-573800D01*
X1160250Y-573950D01*
X1161000Y-578300D01*
X1155900Y-601100D01*
X1154550Y-600650D01*
X1154700Y-593900D01*
X1158900Y-575000D01*
X1159950Y-578000D01*
X1155450Y-599150D01*
X1156950Y-584900D01*
G01X1245000Y-830000D02*
Y-812500D01*
X1242560Y-816000D01*
G01Y-830000D02*
X1247440D01*
G01X1245000Y1315000D02*
Y1332500D01*
X1242560Y1329000D01*
G01Y1315000D02*
X1247440D01*
G01X1419916Y-565000D02*
X1425000Y-547500D01*
X1430084Y-565000D01*
G01X1428253Y-558875D02*
X1421746D01*
G01X1426627Y-20667D02*
X1427440Y-19792D01*
X1428050Y-18334D01*
X1428457Y-16291D01*
X1428050Y-14542D01*
X1427237Y-13375D01*
X1425813Y-12500D01*
X1420323D01*
Y-30000D01*
X1427033D01*
X1428457Y-28834D01*
X1429270Y-27083D01*
X1429677Y-25042D01*
X1429270Y-23000D01*
X1428050Y-21250D01*
X1426627Y-20667D01*
X1420323D01*
G01X1429473Y526041D02*
X1428253Y526917D01*
X1426830Y527500D01*
X1425203D01*
X1423373Y526625D01*
X1421950Y525167D01*
X1420933Y523416D01*
X1420120Y520500D01*
X1419916Y517875D01*
X1420323Y515250D01*
X1420933Y513500D01*
X1422153Y511750D01*
X1423577Y510583D01*
X1425000Y510000D01*
X1426423D01*
X1427847Y510583D01*
X1429067Y511458D01*
X1430084Y512624D01*
G01X1420527Y1050000D02*
Y1067500D01*
X1424593D01*
X1426220Y1066625D01*
X1427440Y1065458D01*
X1428457Y1063709D01*
X1429270Y1061666D01*
X1429473Y1058750D01*
X1429270Y1055833D01*
X1428457Y1053791D01*
X1427440Y1052041D01*
X1426220Y1050875D01*
X1424593Y1050000D01*
X1420527D01*
G54D19*
G01X-1894720Y1212520D02*
Y1218520D01*
X-1892900Y1213520D01*
X-1891080Y1218520D01*
Y1212520D01*
G01X-1888040Y1218520D02*
X-1886360D01*
G01X-1887200D02*
Y1212520D01*
G01X-1888040D02*
X-1886360D01*
G01X-1879960Y1218020D02*
X-1880380Y1218320D01*
X-1880870Y1218520D01*
X-1881430D01*
X-1882060Y1218220D01*
X-1882550Y1217720D01*
X-1882900Y1217120D01*
X-1883180Y1216120D01*
X-1883250Y1215220D01*
X-1883110Y1214320D01*
X-1882900Y1213720D01*
X-1882480Y1213120D01*
X-1881990Y1212720D01*
X-1881500Y1212520D01*
X-1881010D01*
X-1880520Y1212720D01*
X-1880100Y1213020D01*
X-1879750Y1213420D01*
G01X-1877200Y1212520D02*
Y1218520D01*
X-1875450D01*
X-1874890Y1218220D01*
X-1874540Y1217820D01*
X-1874400Y1217020D01*
X-1874540Y1216220D01*
X-1874960Y1215720D01*
X-1875450Y1215420D01*
X-1877200D01*
G01X-1875450D02*
X-1874400Y1212520D01*
G01X-1870100D02*
X-1870660Y1212620D01*
X-1871150Y1213020D01*
X-1871570Y1213620D01*
X-1871850Y1214320D01*
X-1871990Y1215120D01*
Y1215920D01*
X-1871850Y1216720D01*
X-1871570Y1217420D01*
X-1871150Y1218020D01*
X-1870660Y1218420D01*
X-1870100Y1218520D01*
X-1869540Y1218420D01*
X-1869050Y1218020D01*
X-1868630Y1217420D01*
X-1868350Y1216720D01*
X-1868210Y1215920D01*
Y1215120D01*
X-1868350Y1214320D01*
X-1868630Y1213620D01*
X-1869050Y1213020D01*
X-1869540Y1212620D01*
X-1870100Y1212520D01*
G01X-1865870Y1213320D02*
X-1865310Y1212820D01*
X-1864680Y1212520D01*
X-1864120D01*
X-1863560Y1212820D01*
X-1863140Y1213320D01*
X-1862930Y1214020D01*
X-1863070Y1214720D01*
X-1863420Y1215320D01*
X-1864050Y1215720D01*
X-1864890Y1215920D01*
X-1865380Y1216320D01*
X-1865590Y1217020D01*
X-1865450Y1217720D01*
X-1865100Y1218220D01*
X-1864610Y1218520D01*
X-1864120D01*
X-1863630Y1218320D01*
X-1863210Y1217820D01*
G01X-1858700Y1212520D02*
X-1859260Y1212620D01*
X-1859750Y1213020D01*
X-1860170Y1213620D01*
X-1860450Y1214320D01*
X-1860590Y1215120D01*
Y1215920D01*
X-1860450Y1216720D01*
X-1860170Y1217420D01*
X-1859750Y1218020D01*
X-1859260Y1218420D01*
X-1858700Y1218520D01*
X-1858140Y1218420D01*
X-1857650Y1218020D01*
X-1857230Y1217420D01*
X-1856950Y1216720D01*
X-1856810Y1215920D01*
Y1215120D01*
X-1856950Y1214320D01*
X-1857230Y1213620D01*
X-1857650Y1213020D01*
X-1858140Y1212620D01*
X-1858700Y1212520D01*
G01X-1854330D02*
Y1218520D01*
X-1851670D01*
G01X-1852650Y1215620D02*
X-1854330D01*
G01X-1847300Y1218520D02*
Y1212520D01*
G01X-1848910Y1218520D02*
X-1845690D01*
G01X-1834360Y1218020D02*
X-1834780Y1218320D01*
X-1835270Y1218520D01*
X-1835830D01*
X-1836460Y1218220D01*
X-1836950Y1217720D01*
X-1837300Y1217120D01*
X-1837580Y1216120D01*
X-1837650Y1215220D01*
X-1837510Y1214320D01*
X-1837300Y1213720D01*
X-1836880Y1213120D01*
X-1836390Y1212720D01*
X-1835900Y1212520D01*
X-1835410D01*
X-1834920Y1212720D01*
X-1834500Y1213020D01*
X-1834150Y1213420D01*
G01X-1830200Y1212520D02*
X-1830760Y1212620D01*
X-1831250Y1213020D01*
X-1831670Y1213620D01*
X-1831950Y1214320D01*
X-1832090Y1215120D01*
Y1215920D01*
X-1831950Y1216720D01*
X-1831670Y1217420D01*
X-1831250Y1218020D01*
X-1830760Y1218420D01*
X-1830200Y1218520D01*
X-1829640Y1218420D01*
X-1829150Y1218020D01*
X-1828730Y1217420D01*
X-1828450Y1216720D01*
X-1828310Y1215920D01*
Y1215120D01*
X-1828450Y1214320D01*
X-1828730Y1213620D01*
X-1829150Y1213020D01*
X-1829640Y1212620D01*
X-1830200Y1212520D01*
G01X-1825900D02*
Y1218520D01*
X-1824150D01*
X-1823590Y1218220D01*
X-1823240Y1217820D01*
X-1823100Y1217020D01*
X-1823240Y1216220D01*
X-1823660Y1215720D01*
X-1824150Y1215420D01*
X-1825900D01*
G01X-1824150D02*
X-1823100Y1212520D01*
G01X-1820200D02*
Y1218520D01*
X-1818520D01*
X-1817960Y1218220D01*
X-1817540Y1217520D01*
X-1817400Y1216720D01*
X-1817540Y1215920D01*
X-1817890Y1215320D01*
X-1818520Y1215020D01*
X-1820200D01*
G01X-1813100Y1212520D02*
X-1813660Y1212620D01*
X-1814150Y1213020D01*
X-1814570Y1213620D01*
X-1814850Y1214320D01*
X-1814990Y1215120D01*
Y1215920D01*
X-1814850Y1216720D01*
X-1814570Y1217420D01*
X-1814150Y1218020D01*
X-1813660Y1218420D01*
X-1813100Y1218520D01*
X-1812540Y1218420D01*
X-1812050Y1218020D01*
X-1811630Y1217420D01*
X-1811350Y1216720D01*
X-1811210Y1215920D01*
Y1215120D01*
X-1811350Y1214320D01*
X-1811630Y1213620D01*
X-1812050Y1213020D01*
X-1812540Y1212620D01*
X-1813100Y1212520D01*
G01X-1808800D02*
Y1218520D01*
X-1807050D01*
X-1806490Y1218220D01*
X-1806140Y1217820D01*
X-1806000Y1217020D01*
X-1806140Y1216220D01*
X-1806560Y1215720D01*
X-1807050Y1215420D01*
X-1808800D01*
G01X-1807050D02*
X-1806000Y1212520D01*
G01X-1803450D02*
X-1801700Y1218520D01*
X-1799950Y1212520D01*
G01X-1800580Y1214620D02*
X-1802820D01*
G01X-1796000Y1218520D02*
Y1212520D01*
G01X-1797610Y1218520D02*
X-1794390D01*
G01X-1791140D02*
X-1789460D01*
G01X-1790300D02*
Y1212520D01*
G01X-1791140D02*
X-1789460D01*
G01X-1784600D02*
X-1785160Y1212620D01*
X-1785650Y1213020D01*
X-1786070Y1213620D01*
X-1786350Y1214320D01*
X-1786490Y1215120D01*
Y1215920D01*
X-1786350Y1216720D01*
X-1786070Y1217420D01*
X-1785650Y1218020D01*
X-1785160Y1218420D01*
X-1784600Y1218520D01*
X-1784040Y1218420D01*
X-1783550Y1218020D01*
X-1783130Y1217420D01*
X-1782850Y1216720D01*
X-1782710Y1215920D01*
Y1215120D01*
X-1782850Y1214320D01*
X-1783130Y1213620D01*
X-1783550Y1213020D01*
X-1784040Y1212620D01*
X-1784600Y1212520D01*
G01X-1780510D02*
Y1218520D01*
X-1777290Y1212520D01*
Y1218520D01*
G01X-1773200Y1212320D02*
X-1773340Y1212420D01*
Y1212620D01*
X-1773200Y1212720D01*
X-1773060Y1212620D01*
Y1212420D01*
X-1773200Y1212320D01*
G01X-1891360Y1243020D02*
X-1891780Y1243320D01*
X-1892270Y1243520D01*
X-1892830D01*
X-1893460Y1243220D01*
X-1893950Y1242720D01*
X-1894300Y1242120D01*
X-1894580Y1241120D01*
X-1894650Y1240220D01*
X-1894510Y1239320D01*
X-1894300Y1238720D01*
X-1893880Y1238120D01*
X-1893390Y1237720D01*
X-1892900Y1237520D01*
X-1892410D01*
X-1891920Y1237720D01*
X-1891500Y1238020D01*
X-1891150Y1238420D01*
G01X-1887200Y1237520D02*
X-1887760Y1237620D01*
X-1888250Y1238020D01*
X-1888670Y1238620D01*
X-1888950Y1239320D01*
X-1889090Y1240120D01*
Y1240920D01*
X-1888950Y1241720D01*
X-1888670Y1242420D01*
X-1888250Y1243020D01*
X-1887760Y1243420D01*
X-1887200Y1243520D01*
X-1886640Y1243420D01*
X-1886150Y1243020D01*
X-1885730Y1242420D01*
X-1885450Y1241720D01*
X-1885310Y1240920D01*
Y1240120D01*
X-1885450Y1239320D01*
X-1885730Y1238620D01*
X-1886150Y1238020D01*
X-1886640Y1237620D01*
X-1887200Y1237520D01*
G01X-1883110D02*
Y1243520D01*
X-1879890Y1237520D01*
Y1243520D01*
G01X-1875800D02*
Y1237520D01*
G01X-1877410Y1243520D02*
X-1874190D01*
G01X-1868700Y1237520D02*
X-1871500D01*
Y1243520D01*
X-1868700D01*
G01X-1869820Y1240620D02*
X-1871500D01*
G01X-1866010Y1237520D02*
Y1243520D01*
X-1862790Y1237520D01*
Y1243520D01*
G01X-1858700D02*
Y1237520D01*
G01X-1860310Y1243520D02*
X-1857090D01*
G01X-1854470Y1238320D02*
X-1853910Y1237820D01*
X-1853280Y1237520D01*
X-1852720D01*
X-1852160Y1237820D01*
X-1851740Y1238320D01*
X-1851530Y1239020D01*
X-1851670Y1239720D01*
X-1852020Y1240320D01*
X-1852650Y1240720D01*
X-1853490Y1240920D01*
X-1853980Y1241320D01*
X-1854190Y1242020D01*
X-1854050Y1242720D01*
X-1853700Y1243220D01*
X-1853210Y1243520D01*
X-1852720D01*
X-1852230Y1243320D01*
X-1851810Y1242820D01*
G01X-1843420Y1237520D02*
Y1243520D01*
X-1841600Y1238520D01*
X-1839780Y1243520D01*
Y1237520D01*
G01X-1837650D02*
X-1835900Y1243520D01*
X-1834150Y1237520D01*
G01X-1834780Y1239620D02*
X-1837020D01*
G01X-1830200Y1237520D02*
Y1240220D01*
X-1831600Y1243520D01*
G01X-1828800D02*
X-1830200Y1240220D01*
G01X-1820410Y1237520D02*
Y1243520D01*
X-1817190Y1237520D01*
Y1243520D01*
G01X-1813100Y1237520D02*
X-1813660Y1237620D01*
X-1814150Y1238020D01*
X-1814570Y1238620D01*
X-1814850Y1239320D01*
X-1814990Y1240120D01*
Y1240920D01*
X-1814850Y1241720D01*
X-1814570Y1242420D01*
X-1814150Y1243020D01*
X-1813660Y1243420D01*
X-1813100Y1243520D01*
X-1812540Y1243420D01*
X-1812050Y1243020D01*
X-1811630Y1242420D01*
X-1811350Y1241720D01*
X-1811210Y1240920D01*
Y1240120D01*
X-1811350Y1239320D01*
X-1811630Y1238620D01*
X-1812050Y1238020D01*
X-1812540Y1237620D01*
X-1813100Y1237520D01*
G01X-1807400Y1243520D02*
Y1237520D01*
G01X-1809010Y1243520D02*
X-1805790D01*
G01X-1795440Y1240720D02*
X-1795160Y1241020D01*
X-1794950Y1241520D01*
X-1794810Y1242220D01*
X-1794950Y1242820D01*
X-1795230Y1243220D01*
X-1795720Y1243520D01*
X-1797610D01*
Y1237520D01*
X-1795300D01*
X-1794810Y1237920D01*
X-1794530Y1238520D01*
X-1794390Y1239220D01*
X-1794530Y1239920D01*
X-1794950Y1240520D01*
X-1795440Y1240720D01*
X-1797610D01*
G01X-1788900Y1237520D02*
X-1791700D01*
Y1243520D01*
X-1788900D01*
G01X-1790020Y1240620D02*
X-1791700D01*
G01X-1780440Y1237520D02*
Y1243520D01*
X-1779040D01*
X-1778480Y1243220D01*
X-1778060Y1242820D01*
X-1777710Y1242220D01*
X-1777430Y1241520D01*
X-1777360Y1240520D01*
X-1777430Y1239520D01*
X-1777710Y1238820D01*
X-1778060Y1238220D01*
X-1778480Y1237820D01*
X-1779040Y1237520D01*
X-1780440D01*
G01X-1774040Y1243520D02*
X-1772360D01*
G01X-1773200D02*
Y1237520D01*
G01X-1774040D02*
X-1772360D01*
G01X-1768970Y1238320D02*
X-1768410Y1237820D01*
X-1767780Y1237520D01*
X-1767220D01*
X-1766660Y1237820D01*
X-1766240Y1238320D01*
X-1766030Y1239020D01*
X-1766170Y1239720D01*
X-1766520Y1240320D01*
X-1767150Y1240720D01*
X-1767990Y1240920D01*
X-1768480Y1241320D01*
X-1768690Y1242020D01*
X-1768550Y1242720D01*
X-1768200Y1243220D01*
X-1767710Y1243520D01*
X-1767220D01*
X-1766730Y1243320D01*
X-1766310Y1242820D01*
G01X-1760260Y1243020D02*
X-1760680Y1243320D01*
X-1761170Y1243520D01*
X-1761730D01*
X-1762360Y1243220D01*
X-1762850Y1242720D01*
X-1763200Y1242120D01*
X-1763480Y1241120D01*
X-1763550Y1240220D01*
X-1763410Y1239320D01*
X-1763200Y1238720D01*
X-1762780Y1238120D01*
X-1762290Y1237720D01*
X-1761800Y1237520D01*
X-1761310D01*
X-1760820Y1237720D01*
X-1760400Y1238020D01*
X-1760050Y1238420D01*
G01X-1757500Y1243520D02*
Y1237520D01*
X-1754700D01*
G01X-1750400D02*
X-1750960Y1237620D01*
X-1751450Y1238020D01*
X-1751870Y1238620D01*
X-1752150Y1239320D01*
X-1752290Y1240120D01*
Y1240920D01*
X-1752150Y1241720D01*
X-1751870Y1242420D01*
X-1751450Y1243020D01*
X-1750960Y1243420D01*
X-1750400Y1243520D01*
X-1749840Y1243420D01*
X-1749350Y1243020D01*
X-1748930Y1242420D01*
X-1748650Y1241720D01*
X-1748510Y1240920D01*
Y1240120D01*
X-1748650Y1239320D01*
X-1748930Y1238620D01*
X-1749350Y1238020D01*
X-1749840Y1237620D01*
X-1750400Y1237520D01*
G01X-1746170Y1238320D02*
X-1745610Y1237820D01*
X-1744980Y1237520D01*
X-1744420D01*
X-1743860Y1237820D01*
X-1743440Y1238320D01*
X-1743230Y1239020D01*
X-1743370Y1239720D01*
X-1743720Y1240320D01*
X-1744350Y1240720D01*
X-1745190Y1240920D01*
X-1745680Y1241320D01*
X-1745890Y1242020D01*
X-1745750Y1242720D01*
X-1745400Y1243220D01*
X-1744910Y1243520D01*
X-1744420D01*
X-1743930Y1243320D01*
X-1743510Y1242820D01*
G01X-1737600Y1237520D02*
X-1740400D01*
Y1243520D01*
X-1737600D01*
G01X-1738720Y1240620D02*
X-1740400D01*
G01X-1734840Y1237520D02*
Y1243520D01*
X-1733440D01*
X-1732880Y1243220D01*
X-1732460Y1242820D01*
X-1732110Y1242220D01*
X-1731830Y1241520D01*
X-1731760Y1240520D01*
X-1731830Y1239520D01*
X-1732110Y1238820D01*
X-1732460Y1238220D01*
X-1732880Y1237820D01*
X-1733440Y1237520D01*
X-1734840D01*
G01X-1724000Y1243520D02*
X-1723020Y1237520D01*
X-1721900Y1243520D01*
X-1720780Y1237520D01*
X-1719800Y1243520D01*
G01X-1717040D02*
X-1715360D01*
G01X-1716200D02*
Y1237520D01*
G01X-1717040D02*
X-1715360D01*
G01X-1710500Y1243520D02*
Y1237520D01*
G01X-1712110Y1243520D02*
X-1708890D01*
G01X-1706270Y1237520D02*
Y1243520D01*
G01X-1703330D02*
Y1237520D01*
G01Y1240520D02*
X-1706270D01*
G01X-1700010Y1239520D02*
X-1698190D01*
G01X-1892900Y1225000D02*
X-1893460Y1225100D01*
X-1893950Y1225500D01*
X-1894370Y1226100D01*
X-1894650Y1226800D01*
X-1894790Y1227600D01*
Y1228400D01*
X-1894650Y1229200D01*
X-1894370Y1229900D01*
X-1893950Y1230500D01*
X-1893460Y1230900D01*
X-1892900Y1231000D01*
X-1892340Y1230900D01*
X-1891850Y1230500D01*
X-1891430Y1229900D01*
X-1891150Y1229200D01*
X-1891010Y1228400D01*
Y1227600D01*
X-1891150Y1226800D01*
X-1891430Y1226100D01*
X-1891850Y1225500D01*
X-1892340Y1225100D01*
X-1892900Y1225000D01*
G01X-1888740Y1231000D02*
Y1226700D01*
X-1888460Y1225800D01*
X-1887900Y1225200D01*
X-1887200Y1225000D01*
X-1886500Y1225200D01*
X-1885940Y1225800D01*
X-1885660Y1226700D01*
Y1231000D01*
G01X-1881500D02*
Y1225000D01*
G01X-1883110Y1231000D02*
X-1879890D01*
G01X-1870100D02*
Y1225000D01*
G01X-1871710Y1231000D02*
X-1868490D01*
G01X-1865870Y1225000D02*
Y1231000D01*
G01X-1862930D02*
Y1225000D01*
G01Y1228000D02*
X-1865870D01*
G01X-1857300Y1225000D02*
X-1860100D01*
Y1231000D01*
X-1857300D01*
G01X-1858420Y1228100D02*
X-1860100D01*
G01X-1848700Y1225000D02*
Y1231000D01*
X-1847020D01*
X-1846460Y1230700D01*
X-1846040Y1230000D01*
X-1845900Y1229200D01*
X-1846040Y1228400D01*
X-1846390Y1227800D01*
X-1847020Y1227500D01*
X-1848700D01*
G01X-1843000Y1225000D02*
Y1231000D01*
X-1841250D01*
X-1840690Y1230700D01*
X-1840340Y1230300D01*
X-1840200Y1229500D01*
X-1840340Y1228700D01*
X-1840760Y1228200D01*
X-1841250Y1227900D01*
X-1843000D01*
G01X-1841250D02*
X-1840200Y1225000D01*
G01X-1836740Y1231000D02*
X-1835060D01*
G01X-1835900D02*
Y1225000D01*
G01X-1836740D02*
X-1835060D01*
G01X-1830200D02*
X-1830760Y1225100D01*
X-1831250Y1225500D01*
X-1831670Y1226100D01*
X-1831950Y1226800D01*
X-1832090Y1227600D01*
Y1228400D01*
X-1831950Y1229200D01*
X-1831670Y1229900D01*
X-1831250Y1230500D01*
X-1830760Y1230900D01*
X-1830200Y1231000D01*
X-1829640Y1230900D01*
X-1829150Y1230500D01*
X-1828730Y1229900D01*
X-1828450Y1229200D01*
X-1828310Y1228400D01*
Y1227600D01*
X-1828450Y1226800D01*
X-1828730Y1226100D01*
X-1829150Y1225500D01*
X-1829640Y1225100D01*
X-1830200Y1225000D01*
G01X-1825900D02*
Y1231000D01*
X-1824150D01*
X-1823590Y1230700D01*
X-1823240Y1230300D01*
X-1823100Y1229500D01*
X-1823240Y1228700D01*
X-1823660Y1228200D01*
X-1824150Y1227900D01*
X-1825900D01*
G01X-1824150D02*
X-1823100Y1225000D01*
G01X-1815200Y1231000D02*
X-1814220Y1225000D01*
X-1813100Y1231000D01*
X-1811980Y1225000D01*
X-1811000Y1231000D01*
G01X-1808800Y1225000D02*
Y1231000D01*
X-1807050D01*
X-1806490Y1230700D01*
X-1806140Y1230300D01*
X-1806000Y1229500D01*
X-1806140Y1228700D01*
X-1806560Y1228200D01*
X-1807050Y1227900D01*
X-1808800D01*
G01X-1807050D02*
X-1806000Y1225000D01*
G01X-1802540Y1231000D02*
X-1800860D01*
G01X-1801700D02*
Y1225000D01*
G01X-1802540D02*
X-1800860D01*
G01X-1796000Y1231000D02*
Y1225000D01*
G01X-1797610Y1231000D02*
X-1794390D01*
G01X-1790300D02*
Y1225000D01*
G01X-1791910Y1231000D02*
X-1788690D01*
G01X-1783200Y1225000D02*
X-1786000D01*
Y1231000D01*
X-1783200D01*
G01X-1784320Y1228100D02*
X-1786000D01*
G01X-1780510Y1225000D02*
Y1231000D01*
X-1777290Y1225000D01*
Y1231000D01*
G01X-1765960Y1230500D02*
X-1766380Y1230800D01*
X-1766870Y1231000D01*
X-1767430D01*
X-1768060Y1230700D01*
X-1768550Y1230200D01*
X-1768900Y1229600D01*
X-1769180Y1228600D01*
X-1769250Y1227700D01*
X-1769110Y1226800D01*
X-1768900Y1226200D01*
X-1768480Y1225600D01*
X-1767990Y1225200D01*
X-1767500Y1225000D01*
X-1767010D01*
X-1766520Y1225200D01*
X-1766100Y1225500D01*
X-1765750Y1225900D01*
G01X-1761800Y1225000D02*
X-1762360Y1225100D01*
X-1762850Y1225500D01*
X-1763270Y1226100D01*
X-1763550Y1226800D01*
X-1763690Y1227600D01*
Y1228400D01*
X-1763550Y1229200D01*
X-1763270Y1229900D01*
X-1762850Y1230500D01*
X-1762360Y1230900D01*
X-1761800Y1231000D01*
X-1761240Y1230900D01*
X-1760750Y1230500D01*
X-1760330Y1229900D01*
X-1760050Y1229200D01*
X-1759910Y1228400D01*
Y1227600D01*
X-1760050Y1226800D01*
X-1760330Y1226100D01*
X-1760750Y1225500D01*
X-1761240Y1225100D01*
X-1761800Y1225000D01*
G01X-1757710D02*
Y1231000D01*
X-1754490Y1225000D01*
Y1231000D01*
G01X-1751870Y1225800D02*
X-1751310Y1225300D01*
X-1750680Y1225000D01*
X-1750120D01*
X-1749560Y1225300D01*
X-1749140Y1225800D01*
X-1748930Y1226500D01*
X-1749070Y1227200D01*
X-1749420Y1227800D01*
X-1750050Y1228200D01*
X-1750890Y1228400D01*
X-1751380Y1228800D01*
X-1751590Y1229500D01*
X-1751450Y1230200D01*
X-1751100Y1230700D01*
X-1750610Y1231000D01*
X-1750120D01*
X-1749630Y1230800D01*
X-1749210Y1230300D01*
G01X-1743300Y1225000D02*
X-1746100D01*
Y1231000D01*
X-1743300D01*
G01X-1744420Y1228100D02*
X-1746100D01*
G01X-1740610Y1225000D02*
Y1231000D01*
X-1737390Y1225000D01*
Y1231000D01*
G01X-1733300D02*
Y1225000D01*
G01X-1734910Y1231000D02*
X-1731690D01*
G01X-1721900Y1225000D02*
X-1722460Y1225100D01*
X-1722950Y1225500D01*
X-1723370Y1226100D01*
X-1723650Y1226800D01*
X-1723790Y1227600D01*
Y1228400D01*
X-1723650Y1229200D01*
X-1723370Y1229900D01*
X-1722950Y1230500D01*
X-1722460Y1230900D01*
X-1721900Y1231000D01*
X-1721340Y1230900D01*
X-1720850Y1230500D01*
X-1720430Y1229900D01*
X-1720150Y1229200D01*
X-1720010Y1228400D01*
Y1227600D01*
X-1720150Y1226800D01*
X-1720430Y1226100D01*
X-1720850Y1225500D01*
X-1721340Y1225100D01*
X-1721900Y1225000D01*
G01X-1717530D02*
Y1231000D01*
X-1714870D01*
G01X-1715850Y1228100D02*
X-1717530D01*
G01X-1893740Y1256000D02*
X-1892060D01*
G01X-1892900D02*
Y1250000D01*
G01X-1893740D02*
X-1892060D01*
G01X-1888670Y1250800D02*
X-1888110Y1250300D01*
X-1887480Y1250000D01*
X-1886920D01*
X-1886360Y1250300D01*
X-1885940Y1250800D01*
X-1885730Y1251500D01*
X-1885870Y1252200D01*
X-1886220Y1252800D01*
X-1886850Y1253200D01*
X-1887690Y1253400D01*
X-1888180Y1253800D01*
X-1888390Y1254500D01*
X-1888250Y1255200D01*
X-1887900Y1255700D01*
X-1887410Y1256000D01*
X-1886920D01*
X-1886430Y1255800D01*
X-1886010Y1255300D01*
G01X-1877200Y1250000D02*
Y1256000D01*
X-1875450D01*
X-1874890Y1255700D01*
X-1874540Y1255300D01*
X-1874400Y1254500D01*
X-1874540Y1253700D01*
X-1874960Y1253200D01*
X-1875450Y1252900D01*
X-1877200D01*
G01X-1875450D02*
X-1874400Y1250000D01*
G01X-1868700D02*
X-1871500D01*
Y1256000D01*
X-1868700D01*
G01X-1869820Y1253100D02*
X-1871500D01*
G01X-1862860Y1255500D02*
X-1863280Y1255800D01*
X-1863770Y1256000D01*
X-1864330D01*
X-1864960Y1255700D01*
X-1865450Y1255200D01*
X-1865800Y1254600D01*
X-1866080Y1253600D01*
X-1866150Y1252700D01*
X-1866010Y1251800D01*
X-1865800Y1251200D01*
X-1865380Y1250600D01*
X-1864890Y1250200D01*
X-1864400Y1250000D01*
X-1863910D01*
X-1863420Y1250200D01*
X-1863000Y1250500D01*
X-1862650Y1250900D01*
G01X-1857300Y1250000D02*
X-1860100D01*
Y1256000D01*
X-1857300D01*
G01X-1858420Y1253100D02*
X-1860100D01*
G01X-1853840Y1256000D02*
X-1852160D01*
G01X-1853000D02*
Y1250000D01*
G01X-1853840D02*
X-1852160D01*
G01X-1849050Y1256000D02*
X-1847300Y1250000D01*
X-1845550Y1256000D01*
G01X-1840200Y1250000D02*
X-1843000D01*
Y1256000D01*
X-1840200D01*
G01X-1841320Y1253100D02*
X-1843000D01*
G01X-1837440Y1250000D02*
Y1256000D01*
X-1836040D01*
X-1835480Y1255700D01*
X-1835060Y1255300D01*
X-1834710Y1254700D01*
X-1834430Y1254000D01*
X-1834360Y1253000D01*
X-1834430Y1252000D01*
X-1834710Y1251300D01*
X-1835060Y1250700D01*
X-1835480Y1250300D01*
X-1836040Y1250000D01*
X-1837440D01*
G01X-1825340Y1256000D02*
X-1823660D01*
G01X-1824500D02*
Y1250000D01*
G01X-1825340D02*
X-1823660D01*
G01X-1820410D02*
Y1256000D01*
X-1817190Y1250000D01*
Y1256000D01*
G01X-1805860Y1255500D02*
X-1806280Y1255800D01*
X-1806770Y1256000D01*
X-1807330D01*
X-1807960Y1255700D01*
X-1808450Y1255200D01*
X-1808800Y1254600D01*
X-1809080Y1253600D01*
X-1809150Y1252700D01*
X-1809010Y1251800D01*
X-1808800Y1251200D01*
X-1808380Y1250600D01*
X-1807890Y1250200D01*
X-1807400Y1250000D01*
X-1806910D01*
X-1806420Y1250200D01*
X-1806000Y1250500D01*
X-1805650Y1250900D01*
G01X-1801700Y1250000D02*
X-1802260Y1250100D01*
X-1802750Y1250500D01*
X-1803170Y1251100D01*
X-1803450Y1251800D01*
X-1803590Y1252600D01*
Y1253400D01*
X-1803450Y1254200D01*
X-1803170Y1254900D01*
X-1802750Y1255500D01*
X-1802260Y1255900D01*
X-1801700Y1256000D01*
X-1801140Y1255900D01*
X-1800650Y1255500D01*
X-1800230Y1254900D01*
X-1799950Y1254200D01*
X-1799810Y1253400D01*
Y1252600D01*
X-1799950Y1251800D01*
X-1800230Y1251100D01*
X-1800650Y1250500D01*
X-1801140Y1250100D01*
X-1801700Y1250000D01*
G01X-1797610D02*
Y1256000D01*
X-1794390Y1250000D01*
Y1256000D01*
G01X-1791630Y1250000D02*
Y1256000D01*
X-1788970D01*
G01X-1789950Y1253100D02*
X-1791630D01*
G01X-1785440Y1256000D02*
X-1783760D01*
G01X-1784600D02*
Y1250000D01*
G01X-1785440D02*
X-1783760D01*
G01X-1780440D02*
Y1256000D01*
X-1779040D01*
X-1778480Y1255700D01*
X-1778060Y1255300D01*
X-1777710Y1254700D01*
X-1777430Y1254000D01*
X-1777360Y1253000D01*
X-1777430Y1252000D01*
X-1777710Y1251300D01*
X-1778060Y1250700D01*
X-1778480Y1250300D01*
X-1779040Y1250000D01*
X-1780440D01*
G01X-1771800D02*
X-1774600D01*
Y1256000D01*
X-1771800D01*
G01X-1772920Y1253100D02*
X-1774600D01*
G01X-1769110Y1250000D02*
Y1256000D01*
X-1765890Y1250000D01*
Y1256000D01*
G01X-1760260Y1255500D02*
X-1760680Y1255800D01*
X-1761170Y1256000D01*
X-1761730D01*
X-1762360Y1255700D01*
X-1762850Y1255200D01*
X-1763200Y1254600D01*
X-1763480Y1253600D01*
X-1763550Y1252700D01*
X-1763410Y1251800D01*
X-1763200Y1251200D01*
X-1762780Y1250600D01*
X-1762290Y1250200D01*
X-1761800Y1250000D01*
X-1761310D01*
X-1760820Y1250200D01*
X-1760400Y1250500D01*
X-1760050Y1250900D01*
G01X-1754700Y1250000D02*
X-1757500D01*
Y1256000D01*
X-1754700D01*
G01X-1755820Y1253100D02*
X-1757500D01*
G01X-1746450Y1250000D02*
X-1744700Y1256000D01*
X-1742950Y1250000D01*
G01X-1743580Y1252100D02*
X-1745820D01*
G01X-1740610Y1250000D02*
Y1256000D01*
X-1737390Y1250000D01*
Y1256000D01*
G01X-1734840Y1250000D02*
Y1256000D01*
X-1733440D01*
X-1732880Y1255700D01*
X-1732460Y1255300D01*
X-1732110Y1254700D01*
X-1731830Y1254000D01*
X-1731760Y1253000D01*
X-1731830Y1252000D01*
X-1732110Y1251300D01*
X-1732460Y1250700D01*
X-1732880Y1250300D01*
X-1733440Y1250000D01*
X-1734840D01*
G01X-1722740Y1256000D02*
X-1721060D01*
G01X-1721900D02*
Y1250000D01*
G01X-1722740D02*
X-1721060D01*
G01X-1716200Y1256000D02*
Y1250000D01*
G01X-1717810Y1256000D02*
X-1714590D01*
G01X-1711970Y1250800D02*
X-1711410Y1250300D01*
X-1710780Y1250000D01*
X-1710220D01*
X-1709660Y1250300D01*
X-1709240Y1250800D01*
X-1709030Y1251500D01*
X-1709170Y1252200D01*
X-1709520Y1252800D01*
X-1710150Y1253200D01*
X-1710990Y1253400D01*
X-1711480Y1253800D01*
X-1711690Y1254500D01*
X-1711550Y1255200D01*
X-1711200Y1255700D01*
X-1710710Y1256000D01*
X-1710220D01*
X-1709730Y1255800D01*
X-1709310Y1255300D01*
G01X-1892900Y1262520D02*
X-1893460Y1262620D01*
X-1893950Y1263020D01*
X-1894370Y1263620D01*
X-1894650Y1264320D01*
X-1894790Y1265120D01*
Y1265920D01*
X-1894650Y1266720D01*
X-1894370Y1267420D01*
X-1893950Y1268020D01*
X-1893460Y1268420D01*
X-1892900Y1268520D01*
X-1892340Y1268420D01*
X-1891850Y1268020D01*
X-1891430Y1267420D01*
X-1891150Y1266720D01*
X-1891010Y1265920D01*
Y1265120D01*
X-1891150Y1264320D01*
X-1891430Y1263620D01*
X-1891850Y1263020D01*
X-1892340Y1262620D01*
X-1892900Y1262520D01*
G01X-1888530D02*
Y1268520D01*
X-1885870D01*
G01X-1886850Y1265620D02*
X-1888530D01*
G01X-1877620Y1262520D02*
Y1268520D01*
X-1875800Y1263520D01*
X-1873980Y1268520D01*
Y1262520D01*
G01X-1870940Y1268520D02*
X-1869260D01*
G01X-1870100D02*
Y1262520D01*
G01X-1870940D02*
X-1869260D01*
G01X-1862860Y1268020D02*
X-1863280Y1268320D01*
X-1863770Y1268520D01*
X-1864330D01*
X-1864960Y1268220D01*
X-1865450Y1267720D01*
X-1865800Y1267120D01*
X-1866080Y1266120D01*
X-1866150Y1265220D01*
X-1866010Y1264320D01*
X-1865800Y1263720D01*
X-1865380Y1263120D01*
X-1864890Y1262720D01*
X-1864400Y1262520D01*
X-1863910D01*
X-1863420Y1262720D01*
X-1863000Y1263020D01*
X-1862650Y1263420D01*
G01X-1860100Y1262520D02*
Y1268520D01*
X-1858350D01*
X-1857790Y1268220D01*
X-1857440Y1267820D01*
X-1857300Y1267020D01*
X-1857440Y1266220D01*
X-1857860Y1265720D01*
X-1858350Y1265420D01*
X-1860100D01*
G01X-1858350D02*
X-1857300Y1262520D01*
G01X-1853000D02*
X-1853560Y1262620D01*
X-1854050Y1263020D01*
X-1854470Y1263620D01*
X-1854750Y1264320D01*
X-1854890Y1265120D01*
Y1265920D01*
X-1854750Y1266720D01*
X-1854470Y1267420D01*
X-1854050Y1268020D01*
X-1853560Y1268420D01*
X-1853000Y1268520D01*
X-1852440Y1268420D01*
X-1851950Y1268020D01*
X-1851530Y1267420D01*
X-1851250Y1266720D01*
X-1851110Y1265920D01*
Y1265120D01*
X-1851250Y1264320D01*
X-1851530Y1263620D01*
X-1851950Y1263020D01*
X-1852440Y1262620D01*
X-1853000Y1262520D01*
G01X-1848770Y1263320D02*
X-1848210Y1262820D01*
X-1847580Y1262520D01*
X-1847020D01*
X-1846460Y1262820D01*
X-1846040Y1263320D01*
X-1845830Y1264020D01*
X-1845970Y1264720D01*
X-1846320Y1265320D01*
X-1846950Y1265720D01*
X-1847790Y1265920D01*
X-1848280Y1266320D01*
X-1848490Y1267020D01*
X-1848350Y1267720D01*
X-1848000Y1268220D01*
X-1847510Y1268520D01*
X-1847020D01*
X-1846530Y1268320D01*
X-1846110Y1267820D01*
G01X-1841600Y1262520D02*
X-1842160Y1262620D01*
X-1842650Y1263020D01*
X-1843070Y1263620D01*
X-1843350Y1264320D01*
X-1843490Y1265120D01*
Y1265920D01*
X-1843350Y1266720D01*
X-1843070Y1267420D01*
X-1842650Y1268020D01*
X-1842160Y1268420D01*
X-1841600Y1268520D01*
X-1841040Y1268420D01*
X-1840550Y1268020D01*
X-1840130Y1267420D01*
X-1839850Y1266720D01*
X-1839710Y1265920D01*
Y1265120D01*
X-1839850Y1264320D01*
X-1840130Y1263620D01*
X-1840550Y1263020D01*
X-1841040Y1262620D01*
X-1841600Y1262520D01*
G01X-1837230D02*
Y1268520D01*
X-1834570D01*
G01X-1835550Y1265620D02*
X-1837230D01*
G01X-1830200Y1268520D02*
Y1262520D01*
G01X-1831810Y1268520D02*
X-1828590D01*
G01X-1817260Y1268020D02*
X-1817680Y1268320D01*
X-1818170Y1268520D01*
X-1818730D01*
X-1819360Y1268220D01*
X-1819850Y1267720D01*
X-1820200Y1267120D01*
X-1820480Y1266120D01*
X-1820550Y1265220D01*
X-1820410Y1264320D01*
X-1820200Y1263720D01*
X-1819780Y1263120D01*
X-1819290Y1262720D01*
X-1818800Y1262520D01*
X-1818310D01*
X-1817820Y1262720D01*
X-1817400Y1263020D01*
X-1817050Y1263420D01*
G01X-1813100Y1262520D02*
X-1813660Y1262620D01*
X-1814150Y1263020D01*
X-1814570Y1263620D01*
X-1814850Y1264320D01*
X-1814990Y1265120D01*
Y1265920D01*
X-1814850Y1266720D01*
X-1814570Y1267420D01*
X-1814150Y1268020D01*
X-1813660Y1268420D01*
X-1813100Y1268520D01*
X-1812540Y1268420D01*
X-1812050Y1268020D01*
X-1811630Y1267420D01*
X-1811350Y1266720D01*
X-1811210Y1265920D01*
Y1265120D01*
X-1811350Y1264320D01*
X-1811630Y1263620D01*
X-1812050Y1263020D01*
X-1812540Y1262620D01*
X-1813100Y1262520D01*
G01X-1808800D02*
Y1268520D01*
X-1807050D01*
X-1806490Y1268220D01*
X-1806140Y1267820D01*
X-1806000Y1267020D01*
X-1806140Y1266220D01*
X-1806560Y1265720D01*
X-1807050Y1265420D01*
X-1808800D01*
G01X-1807050D02*
X-1806000Y1262520D01*
G01X-1803100D02*
Y1268520D01*
X-1801420D01*
X-1800860Y1268220D01*
X-1800440Y1267520D01*
X-1800300Y1266720D01*
X-1800440Y1265920D01*
X-1800790Y1265320D01*
X-1801420Y1265020D01*
X-1803100D01*
G01X-1796000Y1262520D02*
X-1796560Y1262620D01*
X-1797050Y1263020D01*
X-1797470Y1263620D01*
X-1797750Y1264320D01*
X-1797890Y1265120D01*
Y1265920D01*
X-1797750Y1266720D01*
X-1797470Y1267420D01*
X-1797050Y1268020D01*
X-1796560Y1268420D01*
X-1796000Y1268520D01*
X-1795440Y1268420D01*
X-1794950Y1268020D01*
X-1794530Y1267420D01*
X-1794250Y1266720D01*
X-1794110Y1265920D01*
Y1265120D01*
X-1794250Y1264320D01*
X-1794530Y1263620D01*
X-1794950Y1263020D01*
X-1795440Y1262620D01*
X-1796000Y1262520D01*
G01X-1791700D02*
Y1268520D01*
X-1789950D01*
X-1789390Y1268220D01*
X-1789040Y1267820D01*
X-1788900Y1267020D01*
X-1789040Y1266220D01*
X-1789460Y1265720D01*
X-1789950Y1265420D01*
X-1791700D01*
G01X-1789950D02*
X-1788900Y1262520D01*
G01X-1786350D02*
X-1784600Y1268520D01*
X-1782850Y1262520D01*
G01X-1783480Y1264620D02*
X-1785720D01*
G01X-1778900Y1268520D02*
Y1262520D01*
G01X-1780510Y1268520D02*
X-1777290D01*
G01X-1774040D02*
X-1772360D01*
G01X-1773200D02*
Y1262520D01*
G01X-1774040D02*
X-1772360D01*
G01X-1767500D02*
X-1768060Y1262620D01*
X-1768550Y1263020D01*
X-1768970Y1263620D01*
X-1769250Y1264320D01*
X-1769390Y1265120D01*
Y1265920D01*
X-1769250Y1266720D01*
X-1768970Y1267420D01*
X-1768550Y1268020D01*
X-1768060Y1268420D01*
X-1767500Y1268520D01*
X-1766940Y1268420D01*
X-1766450Y1268020D01*
X-1766030Y1267420D01*
X-1765750Y1266720D01*
X-1765610Y1265920D01*
Y1265120D01*
X-1765750Y1264320D01*
X-1766030Y1263620D01*
X-1766450Y1263020D01*
X-1766940Y1262620D01*
X-1767500Y1262520D01*
G01X-1763410D02*
Y1268520D01*
X-1760190Y1262520D01*
Y1268520D01*
G01X-1756100Y1262320D02*
X-1756240Y1262420D01*
Y1262620D01*
X-1756100Y1262720D01*
X-1755960Y1262620D01*
Y1262420D01*
X-1756100Y1262320D01*
G01X-1744700Y1268520D02*
Y1262520D01*
G01X-1746310Y1268520D02*
X-1743090D01*
G01X-1740470Y1262520D02*
Y1268520D01*
G01X-1737530D02*
Y1262520D01*
G01Y1265520D02*
X-1740470D01*
G01X-1734140Y1268520D02*
X-1732460D01*
G01X-1733300D02*
Y1262520D01*
G01X-1734140D02*
X-1732460D01*
G01X-1729070Y1263320D02*
X-1728510Y1262820D01*
X-1727880Y1262520D01*
X-1727320D01*
X-1726760Y1262820D01*
X-1726340Y1263320D01*
X-1726130Y1264020D01*
X-1726270Y1264720D01*
X-1726620Y1265320D01*
X-1727250Y1265720D01*
X-1728090Y1265920D01*
X-1728580Y1266320D01*
X-1728790Y1267020D01*
X-1728650Y1267720D01*
X-1728300Y1268220D01*
X-1727810Y1268520D01*
X-1727320D01*
X-1726830Y1268320D01*
X-1726410Y1267820D01*
G01X-1717740Y1262520D02*
Y1268520D01*
X-1716340D01*
X-1715780Y1268220D01*
X-1715360Y1267820D01*
X-1715010Y1267220D01*
X-1714730Y1266520D01*
X-1714660Y1265520D01*
X-1714730Y1264520D01*
X-1715010Y1263820D01*
X-1715360Y1263220D01*
X-1715780Y1262820D01*
X-1716340Y1262520D01*
X-1717740D01*
G01X-1711900D02*
Y1268520D01*
X-1710150D01*
X-1709590Y1268220D01*
X-1709240Y1267820D01*
X-1709100Y1267020D01*
X-1709240Y1266220D01*
X-1709660Y1265720D01*
X-1710150Y1265420D01*
X-1711900D01*
G01X-1710150D02*
X-1709100Y1262520D01*
G01X-1706550D02*
X-1704800Y1268520D01*
X-1703050Y1262520D01*
G01X-1703680Y1264620D02*
X-1705920D01*
G01X-1701200Y1268520D02*
X-1700220Y1262520D01*
X-1699100Y1268520D01*
X-1697980Y1262520D01*
X-1697000Y1268520D01*
G01X-1694240D02*
X-1692560D01*
G01X-1693400D02*
Y1262520D01*
G01X-1694240D02*
X-1692560D01*
G01X-1689310D02*
Y1268520D01*
X-1686090Y1262520D01*
Y1268520D01*
G01X-1681580Y1265520D02*
X-1680180D01*
Y1263720D01*
X-1680600Y1263120D01*
X-1681090Y1262720D01*
X-1681790Y1262520D01*
X-1682490Y1262720D01*
X-1682980Y1263120D01*
X-1683400Y1263720D01*
X-1683680Y1264420D01*
X-1683820Y1265220D01*
Y1265920D01*
X-1683680Y1266520D01*
X-1683400Y1267220D01*
X-1682980Y1267820D01*
X-1682560Y1268220D01*
X-1682000Y1268520D01*
X-1681510D01*
X-1680950Y1268320D01*
X-1680530Y1267920D01*
G01X-1895000Y1281000D02*
X-1894020Y1275000D01*
X-1892900Y1281000D01*
X-1891780Y1275000D01*
X-1890800Y1281000D01*
G01X-1888670Y1275000D02*
Y1281000D01*
G01X-1885730D02*
Y1275000D01*
G01Y1278000D02*
X-1888670D01*
G01X-1882340Y1281000D02*
X-1880660D01*
G01X-1881500D02*
Y1275000D01*
G01X-1882340D02*
X-1880660D01*
G01X-1874260Y1280500D02*
X-1874680Y1280800D01*
X-1875170Y1281000D01*
X-1875730D01*
X-1876360Y1280700D01*
X-1876850Y1280200D01*
X-1877200Y1279600D01*
X-1877480Y1278600D01*
X-1877550Y1277700D01*
X-1877410Y1276800D01*
X-1877200Y1276200D01*
X-1876780Y1275600D01*
X-1876290Y1275200D01*
X-1875800Y1275000D01*
X-1875310D01*
X-1874820Y1275200D01*
X-1874400Y1275500D01*
X-1874050Y1275900D01*
G01X-1871570Y1275000D02*
Y1281000D01*
G01X-1868630D02*
Y1275000D01*
G01Y1278000D02*
X-1871570D01*
G01X-1859540Y1281000D02*
X-1857860D01*
G01X-1858700D02*
Y1275000D01*
G01X-1859540D02*
X-1857860D01*
G01X-1854470Y1275800D02*
X-1853910Y1275300D01*
X-1853280Y1275000D01*
X-1852720D01*
X-1852160Y1275300D01*
X-1851740Y1275800D01*
X-1851530Y1276500D01*
X-1851670Y1277200D01*
X-1852020Y1277800D01*
X-1852650Y1278200D01*
X-1853490Y1278400D01*
X-1853980Y1278800D01*
X-1854190Y1279500D01*
X-1854050Y1280200D01*
X-1853700Y1280700D01*
X-1853210Y1281000D01*
X-1852720D01*
X-1852230Y1280800D01*
X-1851810Y1280300D01*
G01X-1841600Y1281000D02*
Y1275000D01*
G01X-1843210Y1281000D02*
X-1839990D01*
G01X-1837370Y1275000D02*
Y1281000D01*
G01X-1834430D02*
Y1275000D01*
G01Y1278000D02*
X-1837370D01*
G01X-1828800Y1275000D02*
X-1831600D01*
Y1281000D01*
X-1828800D01*
G01X-1829920Y1278100D02*
X-1831600D01*
G01X-1820200Y1275000D02*
Y1281000D01*
X-1818520D01*
X-1817960Y1280700D01*
X-1817540Y1280000D01*
X-1817400Y1279200D01*
X-1817540Y1278400D01*
X-1817890Y1277800D01*
X-1818520Y1277500D01*
X-1820200D01*
G01X-1814500Y1275000D02*
Y1281000D01*
X-1812750D01*
X-1812190Y1280700D01*
X-1811840Y1280300D01*
X-1811700Y1279500D01*
X-1811840Y1278700D01*
X-1812260Y1278200D01*
X-1812750Y1277900D01*
X-1814500D01*
G01X-1812750D02*
X-1811700Y1275000D01*
G01X-1807400D02*
X-1807960Y1275100D01*
X-1808450Y1275500D01*
X-1808870Y1276100D01*
X-1809150Y1276800D01*
X-1809290Y1277600D01*
Y1278400D01*
X-1809150Y1279200D01*
X-1808870Y1279900D01*
X-1808450Y1280500D01*
X-1807960Y1280900D01*
X-1807400Y1281000D01*
X-1806840Y1280900D01*
X-1806350Y1280500D01*
X-1805930Y1279900D01*
X-1805650Y1279200D01*
X-1805510Y1278400D01*
Y1277600D01*
X-1805650Y1276800D01*
X-1805930Y1276100D01*
X-1806350Y1275500D01*
X-1806840Y1275100D01*
X-1807400Y1275000D01*
G01X-1803100D02*
Y1281000D01*
X-1801420D01*
X-1800860Y1280700D01*
X-1800440Y1280000D01*
X-1800300Y1279200D01*
X-1800440Y1278400D01*
X-1800790Y1277800D01*
X-1801420Y1277500D01*
X-1803100D01*
G01X-1797400Y1275000D02*
Y1281000D01*
X-1795650D01*
X-1795090Y1280700D01*
X-1794740Y1280300D01*
X-1794600Y1279500D01*
X-1794740Y1278700D01*
X-1795160Y1278200D01*
X-1795650Y1277900D01*
X-1797400D01*
G01X-1795650D02*
X-1794600Y1275000D01*
G01X-1791140Y1281000D02*
X-1789460D01*
G01X-1790300D02*
Y1275000D01*
G01X-1791140D02*
X-1789460D01*
G01X-1783200D02*
X-1786000D01*
Y1281000D01*
X-1783200D01*
G01X-1784320Y1278100D02*
X-1786000D01*
G01X-1778900Y1281000D02*
Y1275000D01*
G01X-1780510Y1281000D02*
X-1777290D01*
G01X-1774950Y1275000D02*
X-1773200Y1281000D01*
X-1771450Y1275000D01*
G01X-1772080Y1277100D02*
X-1774320D01*
G01X-1768900Y1275000D02*
Y1281000D01*
X-1767150D01*
X-1766590Y1280700D01*
X-1766240Y1280300D01*
X-1766100Y1279500D01*
X-1766240Y1278700D01*
X-1766660Y1278200D01*
X-1767150Y1277900D01*
X-1768900D01*
G01X-1767150D02*
X-1766100Y1275000D01*
G01X-1761800D02*
Y1277700D01*
X-1763200Y1281000D01*
G01X-1760400D02*
X-1761800Y1277700D01*
G01X-1751800Y1275000D02*
Y1281000D01*
X-1750120D01*
X-1749560Y1280700D01*
X-1749140Y1280000D01*
X-1749000Y1279200D01*
X-1749140Y1278400D01*
X-1749490Y1277800D01*
X-1750120Y1277500D01*
X-1751800D01*
G01X-1746100Y1275000D02*
Y1281000D01*
X-1744350D01*
X-1743790Y1280700D01*
X-1743440Y1280300D01*
X-1743300Y1279500D01*
X-1743440Y1278700D01*
X-1743860Y1278200D01*
X-1744350Y1277900D01*
X-1746100D01*
G01X-1744350D02*
X-1743300Y1275000D01*
G01X-1739000D02*
X-1739560Y1275100D01*
X-1740050Y1275500D01*
X-1740470Y1276100D01*
X-1740750Y1276800D01*
X-1740890Y1277600D01*
Y1278400D01*
X-1740750Y1279200D01*
X-1740470Y1279900D01*
X-1740050Y1280500D01*
X-1739560Y1280900D01*
X-1739000Y1281000D01*
X-1738440Y1280900D01*
X-1737950Y1280500D01*
X-1737530Y1279900D01*
X-1737250Y1279200D01*
X-1737110Y1278400D01*
Y1277600D01*
X-1737250Y1276800D01*
X-1737530Y1276100D01*
X-1737950Y1275500D01*
X-1738440Y1275100D01*
X-1739000Y1275000D01*
G01X-1734700D02*
Y1281000D01*
X-1733020D01*
X-1732460Y1280700D01*
X-1732040Y1280000D01*
X-1731900Y1279200D01*
X-1732040Y1278400D01*
X-1732390Y1277800D01*
X-1733020Y1277500D01*
X-1734700D01*
G01X-1726200Y1275000D02*
X-1729000D01*
Y1281000D01*
X-1726200D01*
G01X-1727320Y1278100D02*
X-1729000D01*
G01X-1723300Y1275000D02*
Y1281000D01*
X-1721550D01*
X-1720990Y1280700D01*
X-1720640Y1280300D01*
X-1720500Y1279500D01*
X-1720640Y1278700D01*
X-1721060Y1278200D01*
X-1721550Y1277900D01*
X-1723300D01*
G01X-1721550D02*
X-1720500Y1275000D01*
G01X-1716200Y1281000D02*
Y1275000D01*
G01X-1717810Y1281000D02*
X-1714590D01*
G01X-1710500Y1275000D02*
Y1277700D01*
X-1711900Y1281000D01*
G01X-1709100D02*
X-1710500Y1277700D01*
G01X-1892900Y1293520D02*
Y1287520D01*
G01X-1894510Y1293520D02*
X-1891290D01*
G01X-1888670Y1287520D02*
Y1293520D01*
G01X-1885730D02*
Y1287520D01*
G01Y1290520D02*
X-1888670D01*
G01X-1882340Y1293520D02*
X-1880660D01*
G01X-1881500D02*
Y1287520D01*
G01X-1882340D02*
X-1880660D01*
G01X-1877270Y1288320D02*
X-1876710Y1287820D01*
X-1876080Y1287520D01*
X-1875520D01*
X-1874960Y1287820D01*
X-1874540Y1288320D01*
X-1874330Y1289020D01*
X-1874470Y1289720D01*
X-1874820Y1290320D01*
X-1875450Y1290720D01*
X-1876290Y1290920D01*
X-1876780Y1291320D01*
X-1876990Y1292020D01*
X-1876850Y1292720D01*
X-1876500Y1293220D01*
X-1876010Y1293520D01*
X-1875520D01*
X-1875030Y1293320D01*
X-1874610Y1292820D01*
G01X-1865940Y1287520D02*
Y1293520D01*
X-1864540D01*
X-1863980Y1293220D01*
X-1863560Y1292820D01*
X-1863210Y1292220D01*
X-1862930Y1291520D01*
X-1862860Y1290520D01*
X-1862930Y1289520D01*
X-1863210Y1288820D01*
X-1863560Y1288220D01*
X-1863980Y1287820D01*
X-1864540Y1287520D01*
X-1865940D01*
G01X-1860100D02*
Y1293520D01*
X-1858350D01*
X-1857790Y1293220D01*
X-1857440Y1292820D01*
X-1857300Y1292020D01*
X-1857440Y1291220D01*
X-1857860Y1290720D01*
X-1858350Y1290420D01*
X-1860100D01*
G01X-1858350D02*
X-1857300Y1287520D01*
G01X-1854750D02*
X-1853000Y1293520D01*
X-1851250Y1287520D01*
G01X-1851880Y1289620D02*
X-1854120D01*
G01X-1849400Y1293520D02*
X-1848420Y1287520D01*
X-1847300Y1293520D01*
X-1846180Y1287520D01*
X-1845200Y1293520D01*
G01X-1842440D02*
X-1840760D01*
G01X-1841600D02*
Y1287520D01*
G01X-1842440D02*
X-1840760D01*
G01X-1837510D02*
Y1293520D01*
X-1834290Y1287520D01*
Y1293520D01*
G01X-1829780Y1290520D02*
X-1828380D01*
Y1288720D01*
X-1828800Y1288120D01*
X-1829290Y1287720D01*
X-1829990Y1287520D01*
X-1830690Y1287720D01*
X-1831180Y1288120D01*
X-1831600Y1288720D01*
X-1831880Y1289420D01*
X-1832020Y1290220D01*
Y1290920D01*
X-1831880Y1291520D01*
X-1831600Y1292220D01*
X-1831180Y1292820D01*
X-1830760Y1293220D01*
X-1830200Y1293520D01*
X-1829710D01*
X-1829150Y1293320D01*
X-1828730Y1292920D01*
G01X-1817260Y1293020D02*
X-1817680Y1293320D01*
X-1818170Y1293520D01*
X-1818730D01*
X-1819360Y1293220D01*
X-1819850Y1292720D01*
X-1820200Y1292120D01*
X-1820480Y1291120D01*
X-1820550Y1290220D01*
X-1820410Y1289320D01*
X-1820200Y1288720D01*
X-1819780Y1288120D01*
X-1819290Y1287720D01*
X-1818800Y1287520D01*
X-1818310D01*
X-1817820Y1287720D01*
X-1817400Y1288020D01*
X-1817050Y1288420D01*
G01X-1813100Y1287520D02*
X-1813660Y1287620D01*
X-1814150Y1288020D01*
X-1814570Y1288620D01*
X-1814850Y1289320D01*
X-1814990Y1290120D01*
Y1290920D01*
X-1814850Y1291720D01*
X-1814570Y1292420D01*
X-1814150Y1293020D01*
X-1813660Y1293420D01*
X-1813100Y1293520D01*
X-1812540Y1293420D01*
X-1812050Y1293020D01*
X-1811630Y1292420D01*
X-1811350Y1291720D01*
X-1811210Y1290920D01*
Y1290120D01*
X-1811350Y1289320D01*
X-1811630Y1288620D01*
X-1812050Y1288020D01*
X-1812540Y1287620D01*
X-1813100Y1287520D01*
G01X-1809010D02*
Y1293520D01*
X-1805790Y1287520D01*
Y1293520D01*
G01X-1801700D02*
Y1287520D01*
G01X-1803310Y1293520D02*
X-1800090D01*
G01X-1797750Y1287520D02*
X-1796000Y1293520D01*
X-1794250Y1287520D01*
G01X-1794880Y1289620D02*
X-1797120D01*
G01X-1791140Y1293520D02*
X-1789460D01*
G01X-1790300D02*
Y1287520D01*
G01X-1791140D02*
X-1789460D01*
G01X-1786210D02*
Y1293520D01*
X-1782990Y1287520D01*
Y1293520D01*
G01X-1780370Y1288320D02*
X-1779810Y1287820D01*
X-1779180Y1287520D01*
X-1778620D01*
X-1778060Y1287820D01*
X-1777640Y1288320D01*
X-1777430Y1289020D01*
X-1777570Y1289720D01*
X-1777920Y1290320D01*
X-1778550Y1290720D01*
X-1779390Y1290920D01*
X-1779880Y1291320D01*
X-1780090Y1292020D01*
X-1779950Y1292720D01*
X-1779600Y1293220D01*
X-1779110Y1293520D01*
X-1778620D01*
X-1778130Y1293320D01*
X-1777710Y1292820D01*
G01X-1768340Y1293520D02*
X-1766660D01*
G01X-1767500D02*
Y1287520D01*
G01X-1768340D02*
X-1766660D01*
G01X-1763410D02*
Y1293520D01*
X-1760190Y1287520D01*
Y1293520D01*
G01X-1757430Y1287520D02*
Y1293520D01*
X-1754770D01*
G01X-1755750Y1290620D02*
X-1757430D01*
G01X-1750400Y1287520D02*
X-1750960Y1287620D01*
X-1751450Y1288020D01*
X-1751870Y1288620D01*
X-1752150Y1289320D01*
X-1752290Y1290120D01*
Y1290920D01*
X-1752150Y1291720D01*
X-1751870Y1292420D01*
X-1751450Y1293020D01*
X-1750960Y1293420D01*
X-1750400Y1293520D01*
X-1749840Y1293420D01*
X-1749350Y1293020D01*
X-1748930Y1292420D01*
X-1748650Y1291720D01*
X-1748510Y1290920D01*
Y1290120D01*
X-1748650Y1289320D01*
X-1748930Y1288620D01*
X-1749350Y1288020D01*
X-1749840Y1287620D01*
X-1750400Y1287520D01*
G01X-1746100D02*
Y1293520D01*
X-1744350D01*
X-1743790Y1293220D01*
X-1743440Y1292820D01*
X-1743300Y1292020D01*
X-1743440Y1291220D01*
X-1743860Y1290720D01*
X-1744350Y1290420D01*
X-1746100D01*
G01X-1744350D02*
X-1743300Y1287520D01*
G01X-1740820D02*
Y1293520D01*
X-1739000Y1288520D01*
X-1737180Y1293520D01*
Y1287520D01*
G01X-1735050D02*
X-1733300Y1293520D01*
X-1731550Y1287520D01*
G01X-1732180Y1289620D02*
X-1734420D01*
G01X-1727600Y1293520D02*
Y1287520D01*
G01X-1729210Y1293520D02*
X-1725990D01*
G01X-1722740D02*
X-1721060D01*
G01X-1721900D02*
Y1287520D01*
G01X-1722740D02*
X-1721060D01*
G01X-1716200D02*
X-1716760Y1287620D01*
X-1717250Y1288020D01*
X-1717670Y1288620D01*
X-1717950Y1289320D01*
X-1718090Y1290120D01*
Y1290920D01*
X-1717950Y1291720D01*
X-1717670Y1292420D01*
X-1717250Y1293020D01*
X-1716760Y1293420D01*
X-1716200Y1293520D01*
X-1715640Y1293420D01*
X-1715150Y1293020D01*
X-1714730Y1292420D01*
X-1714450Y1291720D01*
X-1714310Y1290920D01*
Y1290120D01*
X-1714450Y1289320D01*
X-1714730Y1288620D01*
X-1715150Y1288020D01*
X-1715640Y1287620D01*
X-1716200Y1287520D01*
G01X-1712110D02*
Y1293520D01*
X-1708890Y1287520D01*
Y1293520D01*
M02*
